FILE_TYPE = MACRO_DRAWING;
SET COLOR_WIRE YELLOW;
SET COLOR_PROP ORANGE;
SET COLOR_DOT WHITE;
SET COLOR_ARC YELLOW;
SET COLOR_BODY GREEN;
SET COLOR_NOTE PURPLE;
SET PROP_DISPLAY VALUE;
SET PAGE_NUMBER P175;
FORCEADD OFFPAGE..1
(1600 900);
FORCEPROP 2 LAST $XR0 215 
J 0
(1348 900);
DISPLAY 0.638298 (1348 900);
PAINT MONO (1348 900);
FORCEPROP 2 LAST PATH I101
J 0
(1650 975);
DISPLAY 1.021277 (1650 975);
DISPLAY INVISIBLE (1650 975);
FORCEPROP 1 LAST COMMENT_BODY TRUE
J 0
(1725 800);
DISPLAY 0.872340 (1725 800);
PAINT GREEN (1725 800);
DISPLAY INVISIBLE (1725 800);
FORCEPROP 1 LAST OFFPAGE TRUE
J 0
(1925 775);
DISPLAY 0.872340 (1925 775);
DISPLAY INVISIBLE (1925 775);
FORCEPROP 2 LAST CDS_LIB standard
J 0
(1600 900);
DISPLAY INVISIBLE (1600 900);
FORCEADD Q_RES..1
(2950 900);
FORCEPROP 1 LAST PART_NUMBER CS03322FB03
J 0
(2850 950);
DISPLAY 0.510638 (2850 950);
DISPLAY INVISIBLE (2850 950);
FORCEPROP 1 LAST VALUE 33.2
J 2
(3150 900);
DISPLAY 0.510638 (3150 900);
FORCEPROP 1 LAST TOLERANCE 1%
J 0
(3175 900);
DISPLAY 0.510638 (3175 900);
FORCEPROP 1 LAST MATERIAL CHIP
J 0
(3250 900);
DISPLAY 0.510638 (3250 900);
FORCEPROP 1 LAST $LOCATION R699
J 0
(2700 900);
DISPLAY 0.638298 (2700 900);
FORCEPROP 1 LASTPIN (2850 900) $PN 1
J 0
(2862 912);
DISPLAY 0.787234 (2862 912);
FORCEPROP 1 LASTPIN (3050 900) $PN 2
J 0
(3012 912);
DISPLAY 0.787234 (3012 912);
FORCEPROP 2 LAST CDS_LIB pure_quanta
J 0
(2950 900);
PAINT MONO (2950 900);
DISPLAY INVISIBLE (2950 900);
FORCEPROP 1 LAST PATH I102
J 0
(2900 1050);
DISPLAY 0.978723 (2900 1050);
PAINT WHITE (2900 1050);
DISPLAY INVISIBLE (2900 1050);
FORCEPROP 1 LAST WATTAGE 1/16W
J 2
(3150 1000);
DISPLAY 0.510638 (3150 1000);
DISPLAY INVISIBLE (3150 1000);
FORCEPROP 1 LAST PACK_TYPE 0402LF
J 0
(2850 1000);
DISPLAY 0.510638 (2850 1000);
DISPLAY INVISIBLE (2850 1000);
FORCEPROP 2 LAST CDS_LOCATION R699
J 0
(2900 1100);
DISPLAY 1.021277 (2900 1100);
DISPLAY INVISIBLE (2900 1100);
FORCEPROP 2 LAST $SEC 1
J 0
(2900 1100);
DISPLAY 0.680851 (2900 1100);
PAINT MONO (2900 1100);
DISPLAY INVISIBLE (2900 1100);
FORCEPROP 2 LAST CDS_SEC 1
J 0
(2900 1100);
DISPLAY 1.021277 (2900 1100);
DISPLAY INVISIBLE (2900 1100);
FORCEADD Q_RES..1
(3475 -775);
FORCEPROP 1 LAST PART_NUMBER CS22002FB07
J 0
(3300 -700);
DISPLAY 0.638298 (3300 -700);
DISPLAY INVISIBLE (3300 -700);
FORCEPROP 1 LAST VALUE 2K
J 2
(3650 -775);
DISPLAY 0.638298 (3650 -775);
FORCEPROP 1 LAST TOLERANCE 1%
J 0
(3675 -775);
DISPLAY 0.638298 (3675 -775);
FORCEPROP 1 LAST MATERIAL CHIP
J 0
(3775 -775);
DISPLAY 0.638298 (3775 -775);
FORCEPROP 1 LAST $LOCATION R1451
J 0
(3200 -775);
DISPLAY 0.787234 (3200 -775);
FORCEPROP 1 LASTPIN (3375 -775) $PN 1
J 0
(3387 -763);
DISPLAY 0.787234 (3387 -763);
FORCEPROP 1 LASTPIN (3575 -775) $PN 2
J 0
(3537 -763);
DISPLAY 0.787234 (3537 -763);
FORCEPROP 1 LAST WATTAGE 1/16W
J 2
(3725 -650);
DISPLAY 0.638298 (3725 -650);
DISPLAY INVISIBLE (3725 -650);
FORCEPROP 1 LAST PACK_TYPE 0402LF
J 0
(3300 -650);
DISPLAY 0.638298 (3300 -650);
DISPLAY INVISIBLE (3300 -650);
FORCEPROP 1 LAST PATH I109
J 0
(3425 -625);
DISPLAY 0.978723 (3425 -625);
PAINT WHITE (3425 -625);
DISPLAY INVISIBLE (3425 -625);
FORCEPROP 2 LAST CDS_LIB pure_quanta
J 0
(3475 -775);
PAINT MONO (3475 -775);
DISPLAY INVISIBLE (3475 -775);
FORCEPROP 2 LAST CDS_LOCATION R1451
J 0
(3425 -575);
DISPLAY 1.021277 (3425 -575);
DISPLAY INVISIBLE (3425 -575);
FORCEPROP 2 LAST $SEC 1
J 0
(3425 -575);
DISPLAY 0.680851 (3425 -575);
PAINT MONO (3425 -575);
DISPLAY INVISIBLE (3425 -575);
FORCEPROP 2 LAST CDS_SEC 1
J 0
(3425 -575);
DISPLAY 1.021277 (3425 -575);
DISPLAY INVISIBLE (3425 -575);
FORCEADD OFFPAGE..5
(1925 -775);
FORCEPROP 2 LAST $XR0 183 
J 0
(1670 -775);
DISPLAY 0.638298 (1670 -775);
PAINT MONO (1670 -775);
FORCEPROP 2 LAST PATH I110
J 0
(1650 -725);
DISPLAY 1.021277 (1650 -725);
DISPLAY INVISIBLE (1650 -725);
FORCEPROP 2 LAST CDS_LIB standard
J 0
(1925 -775);
PAINT MONO (1925 -775);
DISPLAY INVISIBLE (1925 -775);
FORCEPROP 1 LAST COMMENT_BODY TRUE
J 0
(2025 -850);
DISPLAY 1.170213 (2025 -850);
PAINT GREEN (2025 -850);
DISPLAY INVISIBLE (2025 -850);
FORCEPROP 1 LAST OFFPAGE TRUE
J 0
(2250 -900);
DISPLAY 0.872340 (2250 -900);
DISPLAY INVISIBLE (2250 -900);
FORCEADD UNIVERSAL_POWER..1
(4525 100);
FORCEPROP 3 LASTPIN (4525 50) SIG_NAME P3V3_AUX\g
J 0
(4535 60);
DISPLAY 0.659574 (4535 60);
PAINT MONO (4535 60);
DISPLAY INVISIBLE (4535 60);
FORCEPROP 1 LAST HDL_POWER P3V3_AUX
J 1
(4525 150);
DISPLAY 0.872340 (4525 150);
PAINT GREEN (4525 150);
FORCEPROP 1 LAST PATH I111
J 0
(4575 125);
DISPLAY 0.872340 (4575 125);
PAINT AQUA (4575 125);
DISPLAY INVISIBLE (4575 125);
FORCEPROP 2 LAST CDS_LIB logical_power
J 0
(4525 100);
PAINT MONO (4525 100);
DISPLAY INVISIBLE (4525 100);
FORCEADD Q_RES..1
(3475 -825);
FORCEPROP 1 LAST PART_NUMBER CS22002FB07
J 0
(3300 -750);
DISPLAY 0.638298 (3300 -750);
DISPLAY INVISIBLE (3300 -750);
FORCEPROP 1 LAST TOLERANCE 1%
J 0
(3675 -825);
DISPLAY 0.638298 (3675 -825);
FORCEPROP 1 LAST MATERIAL CHIP
J 0
(3775 -825);
DISPLAY 0.638298 (3775 -825);
FORCEPROP 1 LAST VALUE 2K
J 2
(3650 -825);
DISPLAY 0.638298 (3650 -825);
FORCEPROP 1 LAST $LOCATION R1452
J 0
(3200 -825);
DISPLAY 0.787234 (3200 -825);
FORCEPROP 1 LASTPIN (3375 -825) $PN 1
J 0
(3387 -813);
DISPLAY 0.787234 (3387 -813);
FORCEPROP 1 LASTPIN (3575 -825) $PN 2
J 0
(3537 -813);
DISPLAY 0.787234 (3537 -813);
FORCEPROP 1 LAST PACK_TYPE 0402LF
J 0
(3300 -700);
DISPLAY 0.638298 (3300 -700);
DISPLAY INVISIBLE (3300 -700);
FORCEPROP 1 LAST WATTAGE 1/16W
J 2
(3725 -700);
DISPLAY 0.638298 (3725 -700);
DISPLAY INVISIBLE (3725 -700);
FORCEPROP 1 LAST PATH I112
J 0
(3425 -675);
DISPLAY 0.978723 (3425 -675);
PAINT WHITE (3425 -675);
DISPLAY INVISIBLE (3425 -675);
FORCEPROP 2 LAST CDS_LIB pure_quanta
J 0
(3475 -825);
PAINT MONO (3475 -825);
DISPLAY INVISIBLE (3475 -825);
FORCEPROP 2 LAST CDS_LOCATION R1452
J 0
(3425 -625);
DISPLAY 1.021277 (3425 -625);
DISPLAY INVISIBLE (3425 -625);
FORCEPROP 2 LAST $SEC 1
J 0
(3425 -625);
DISPLAY 0.680851 (3425 -625);
PAINT MONO (3425 -625);
DISPLAY INVISIBLE (3425 -625);
FORCEPROP 2 LAST CDS_SEC 1
J 0
(3425 -625);
DISPLAY 1.021277 (3425 -625);
DISPLAY INVISIBLE (3425 -625);
FORCEADD OFFPAGE..5
(1925 -825);
FORCEPROP 2 LAST $XR0 183 
J 0
(1670 -825);
DISPLAY 0.638298 (1670 -825);
PAINT MONO (1670 -825);
FORCEPROP 2 LAST PATH I113
J 0
(1650 -775);
DISPLAY 1.021277 (1650 -775);
DISPLAY INVISIBLE (1650 -775);
FORCEPROP 1 LAST OFFPAGE TRUE
J 0
(2250 -950);
DISPLAY 0.872340 (2250 -950);
DISPLAY INVISIBLE (2250 -950);
FORCEPROP 1 LAST COMMENT_BODY TRUE
J 0
(2025 -900);
DISPLAY 1.170213 (2025 -900);
PAINT GREEN (2025 -900);
DISPLAY INVISIBLE (2025 -900);
FORCEPROP 2 LAST CDS_LIB standard
J 0
(1925 -825);
PAINT MONO (1925 -825);
DISPLAY INVISIBLE (1925 -825);
FORCEADD OFFPAGE..5
(1925 -975);
FORCEPROP 2 LAST $XR0 183 
J 0
(1670 -975);
DISPLAY 0.638298 (1670 -975);
PAINT MONO (1670 -975);
FORCEPROP 2 LAST PATH I118
J 0
(1650 -925);
DISPLAY 1.021277 (1650 -925);
DISPLAY INVISIBLE (1650 -925);
FORCEPROP 1 LAST OFFPAGE TRUE
J 0
(2250 -1100);
DISPLAY 0.872340 (2250 -1100);
DISPLAY INVISIBLE (2250 -1100);
FORCEPROP 1 LAST COMMENT_BODY TRUE
J 0
(2025 -1050);
DISPLAY 1.170213 (2025 -1050);
PAINT GREEN (2025 -1050);
DISPLAY INVISIBLE (2025 -1050);
FORCEPROP 2 LAST CDS_LIB standard
J 0
(1925 -975);
PAINT MONO (1925 -975);
DISPLAY INVISIBLE (1925 -975);
FORCEADD OFFPAGE..5
(1925 -925);
FORCEPROP 2 LAST $XR0 183 
J 0
(1670 -925);
DISPLAY 0.638298 (1670 -925);
PAINT MONO (1670 -925);
FORCEPROP 2 LAST PATH I119
J 0
(1650 -875);
DISPLAY 1.021277 (1650 -875);
DISPLAY INVISIBLE (1650 -875);
FORCEPROP 2 LAST CDS_LIB standard
J 0
(1925 -925);
PAINT MONO (1925 -925);
DISPLAY INVISIBLE (1925 -925);
FORCEPROP 1 LAST COMMENT_BODY TRUE
J 0
(2025 -1000);
DISPLAY 1.170213 (2025 -1000);
PAINT GREEN (2025 -1000);
DISPLAY INVISIBLE (2025 -1000);
FORCEPROP 1 LAST OFFPAGE TRUE
J 0
(2250 -1050);
DISPLAY 0.872340 (2250 -1050);
DISPLAY INVISIBLE (2250 -1050);
FORCEADD Q_RES..1
(3475 -925);
FORCEPROP 1 LAST PART_NUMBER CS22002FB07
J 0
(3300 -850);
DISPLAY 0.638298 (3300 -850);
DISPLAY INVISIBLE (3300 -850);
FORCEPROP 1 LAST MATERIAL CHIP
J 0
(3775 -925);
DISPLAY 0.638298 (3775 -925);
FORCEPROP 1 LAST TOLERANCE 1%
J 0
(3675 -925);
DISPLAY 0.638298 (3675 -925);
FORCEPROP 1 LAST VALUE 2K
J 2
(3650 -925);
DISPLAY 0.638298 (3650 -925);
FORCEPROP 1 LAST $LOCATION R1453
J 0
(3200 -925);
DISPLAY 0.787234 (3200 -925);
FORCEPROP 1 LASTPIN (3375 -925) $PN 1
J 0
(3387 -913);
DISPLAY 0.787234 (3387 -913);
FORCEPROP 1 LASTPIN (3575 -925) $PN 2
J 0
(3537 -913);
DISPLAY 0.787234 (3537 -913);
FORCEPROP 2 LAST CDS_LIB pure_quanta
J 0
(3475 -925);
PAINT MONO (3475 -925);
DISPLAY INVISIBLE (3475 -925);
FORCEPROP 1 LAST PATH I120
J 0
(3425 -775);
DISPLAY 0.978723 (3425 -775);
PAINT WHITE (3425 -775);
DISPLAY INVISIBLE (3425 -775);
FORCEPROP 1 LAST WATTAGE 1/16W
J 2
(3725 -800);
DISPLAY 0.638298 (3725 -800);
DISPLAY INVISIBLE (3725 -800);
FORCEPROP 1 LAST PACK_TYPE 0402LF
J 0
(3300 -800);
DISPLAY 0.638298 (3300 -800);
DISPLAY INVISIBLE (3300 -800);
FORCEPROP 2 LAST CDS_LOCATION R1453
J 0
(3425 -725);
DISPLAY 1.021277 (3425 -725);
DISPLAY INVISIBLE (3425 -725);
FORCEPROP 2 LAST $SEC 1
J 0
(3425 -725);
DISPLAY 0.680851 (3425 -725);
PAINT MONO (3425 -725);
DISPLAY INVISIBLE (3425 -725);
FORCEPROP 2 LAST CDS_SEC 1
J 0
(3425 -725);
DISPLAY 1.021277 (3425 -725);
DISPLAY INVISIBLE (3425 -725);
FORCEADD Q_RES..1
(3475 -975);
FORCEPROP 1 LAST PART_NUMBER CS22002FB07
J 0
(3300 -900);
DISPLAY 0.638298 (3300 -900);
DISPLAY INVISIBLE (3300 -900);
FORCEPROP 1 LAST TOLERANCE 1%
J 0
(3675 -975);
DISPLAY 0.638298 (3675 -975);
FORCEPROP 1 LAST MATERIAL CHIP
J 0
(3775 -975);
DISPLAY 0.638298 (3775 -975);
FORCEPROP 1 LAST VALUE 2K
J 2
(3650 -975);
DISPLAY 0.638298 (3650 -975);
FORCEPROP 1 LAST $LOCATION R1454
J 0
(3200 -975);
DISPLAY 0.787234 (3200 -975);
FORCEPROP 1 LASTPIN (3375 -975) $PN 1
J 0
(3387 -963);
DISPLAY 0.787234 (3387 -963);
FORCEPROP 1 LASTPIN (3575 -975) $PN 2
J 0
(3537 -963);
DISPLAY 0.787234 (3537 -963);
FORCEPROP 2 LAST CDS_LIB pure_quanta
J 0
(3475 -975);
PAINT MONO (3475 -975);
DISPLAY INVISIBLE (3475 -975);
FORCEPROP 1 LAST PACK_TYPE 0402LF
J 0
(3300 -850);
DISPLAY 0.638298 (3300 -850);
DISPLAY INVISIBLE (3300 -850);
FORCEPROP 1 LAST WATTAGE 1/16W
J 2
(3725 -850);
DISPLAY 0.638298 (3725 -850);
DISPLAY INVISIBLE (3725 -850);
FORCEPROP 1 LAST PATH I121
J 0
(3425 -825);
DISPLAY 0.978723 (3425 -825);
PAINT WHITE (3425 -825);
DISPLAY INVISIBLE (3425 -825);
FORCEPROP 2 LAST CDS_LOCATION R1454
J 0
(3425 -775);
DISPLAY 1.021277 (3425 -775);
DISPLAY INVISIBLE (3425 -775);
FORCEPROP 2 LAST $SEC 1
J 0
(3425 -775);
DISPLAY 0.680851 (3425 -775);
PAINT MONO (3425 -775);
DISPLAY INVISIBLE (3425 -775);
FORCEPROP 2 LAST CDS_SEC 1
J 0
(3425 -775);
DISPLAY 1.021277 (3425 -775);
DISPLAY INVISIBLE (3425 -775);
FORCEADD Q_RES..1
(2950 300);
FORCEPROP 1 LAST PART_NUMBER CS11002FB07
J 0
(2750 400);
DISPLAY 0.638298 (2750 400);
DISPLAY INVISIBLE (2750 400);
FORCEPROP 1 LAST VALUE 100
J 2
(3150 300);
DISPLAY 0.638298 (3150 300);
FORCEPROP 1 LAST PACK_TYPE 0402LF
J 0
(2750 450);
DISPLAY 0.638298 (2750 450);
FORCEPROP 1 LAST WATTAGE 1/16W
J 2
(3150 450);
DISPLAY 0.638298 (3150 450);
FORCEPROP 1 LAST MATERIAL CHIP
J 0
(3250 300);
DISPLAY 0.638298 (3250 300);
FORCEPROP 1 LAST TOLERANCE 1%
J 0
(3175 300);
DISPLAY 0.638298 (3175 300);
FORCEPROP 1 LAST $LOCATION R1487
J 0
(2700 300);
DISPLAY 0.638298 (2700 300);
FORCEPROP 1 LASTPIN (2850 300) $PN 1
J 0
(2862 312);
DISPLAY 0.787234 (2862 312);
FORCEPROP 1 LASTPIN (3050 300) $PN 2
J 0
(3012 312);
DISPLAY 0.787234 (3012 312);
FORCEPROP 2 LAST CDS_LIB pure_quanta
J 0
(2950 300);
PAINT MONO (2950 300);
DISPLAY INVISIBLE (2950 300);
FORCEPROP 1 LAST PATH I125
J 0
(2900 450);
DISPLAY 0.978723 (2900 450);
PAINT WHITE (2900 450);
DISPLAY INVISIBLE (2900 450);
FORCEPROP 2 LAST CDS_LOCATION R1487
J 0
(3150 500);
DISPLAY 1.021277 (3150 500);
DISPLAY INVISIBLE (3150 500);
FORCEPROP 2 LAST $SEC 1
J 0
(3150 500);
DISPLAY 0.680851 (3150 500);
PAINT MONO (3150 500);
DISPLAY INVISIBLE (3150 500);
FORCEPROP 2 LAST CDS_SEC 1
J 0
(3150 500);
DISPLAY 1.021277 (3150 500);
DISPLAY INVISIBLE (3150 500);
FORCEADD UNIVERSAL_GND..1
(3450 175);
FORCEPROP 3 LASTPIN (3450 225) SIG_NAME GND\g
J 0
(3460 235);
DISPLAY 0.659574 (3460 235);
PAINT MONO (3460 235);
DISPLAY INVISIBLE (3460 235);
FORCEPROP 2 LAST CDS_LIB logical_power
J 0
(3450 175);
PAINT MONO (3450 175);
DISPLAY INVISIBLE (3450 175);
FORCEPROP 1 LAST PATH I126
J 0
(3525 175);
DISPLAY 0.872340 (3525 175);
PAINT AQUA (3525 175);
DISPLAY INVISIBLE (3525 175);
FORCEPROP 1 LAST HDL_POWER GND
J 1
(3475 100);
DISPLAY 0.872340 (3475 100);
PAINT GREEN (3475 100);
DISPLAY INVISIBLE (3475 100);
FORCEADD OFFPAGE..1
(1600 300);
FORCEPROP 2 LAST $XR1 183 
J 0
(1228 300);
DISPLAY 0.638298 (1228 300);
PAINT MONO (1228 300);
FORCEPROP 2 LAST $XR0 194 
J 0
(1348 300);
DISPLAY 0.638298 (1348 300);
PAINT MONO (1348 300);
FORCEPROP 2 LAST CDS_LIB standard
J 0
(1600 300);
DISPLAY INVISIBLE (1600 300);
FORCEPROP 1 LAST OFFPAGE TRUE
J 0
(1925 175);
DISPLAY 0.872340 (1925 175);
DISPLAY INVISIBLE (1925 175);
FORCEPROP 1 LAST COMMENT_BODY TRUE
J 0
(1725 200);
DISPLAY 0.872340 (1725 200);
PAINT GREEN (1725 200);
DISPLAY INVISIBLE (1725 200);
FORCEPROP 2 LAST PATH I131
J 0
(1325 350);
DISPLAY 1.021277 (1325 350);
DISPLAY INVISIBLE (1325 350);
FORCEADD OFFPAGE..1
(-1925 3950);
FORCEPROP 2 LAST $XR0 190 
J 0
(-2207 3950);
DISPLAY 0.638298 (-2207 3950);
PAINT MONO (-2207 3950);
FORCEPROP 1 LAST COMMENT_BODY TRUE
J 0
(-1800 3850);
DISPLAY 1.170213 (-1800 3850);
PAINT GREEN (-1800 3850);
DISPLAY INVISIBLE (-1800 3850);
FORCEPROP 1 LAST OFFPAGE TRUE
J 0
(-1600 3825);
DISPLAY 0.872340 (-1600 3825);
DISPLAY INVISIBLE (-1600 3825);
FORCEPROP 2 LAST PATH I132
J 0
(-2225 4000);
DISPLAY 1.021277 (-2225 4000);
DISPLAY INVISIBLE (-2225 4000);
FORCEPROP 2 LAST CDS_LIB standard
J 0
(-1925 3950);
PAINT MONO (-1925 3950);
DISPLAY INVISIBLE (-1925 3950);
FORCEADD OFFPAGE..1
R 2
(4450 2150);
FORCEPROP 2 LAST $XR0 241 
J 0
(4666 2150);
DISPLAY 0.638298 (4666 2150);
PAINT MONO (4666 2150);
FORCEPROP 2 LAST CDS_LIB standard
J 0
(4450 2150);
PAINT MONO (4450 2150);
DISPLAY INVISIBLE (4450 2150);
FORCEPROP 2 LAST PATH I134
J 0
(4800 2200);
DISPLAY 1.021277 (4800 2200);
DISPLAY INVISIBLE (4800 2200);
FORCEPROP 1 LAST COMMENT_BODY TRUE
J 2
(4325 2050);
DISPLAY 0.872340 (4325 2050);
PAINT GREEN (4325 2050);
DISPLAY INVISIBLE (4325 2050);
FORCEPROP 1 LAST OFFPAGE TRUE
J 2
(4125 2025);
DISPLAY 0.872340 (4125 2025);
DISPLAY INVISIBLE (4125 2025);
FORCEADD OFFPAGE..5
(1925 -625);
FORCEPROP 2 LAST $XR0 183 
J 0
(1670 -625);
DISPLAY 0.638298 (1670 -625);
PAINT MONO (1670 -625);
FORCEPROP 2 LAST PATH I135
J 0
(1650 -575);
DISPLAY 1.021277 (1650 -575);
DISPLAY INVISIBLE (1650 -575);
FORCEPROP 1 LAST OFFPAGE TRUE
J 0
(2250 -750);
DISPLAY 0.872340 (2250 -750);
DISPLAY INVISIBLE (2250 -750);
FORCEPROP 1 LAST COMMENT_BODY TRUE
J 0
(2025 -700);
DISPLAY 1.170213 (2025 -700);
PAINT GREEN (2025 -700);
DISPLAY INVISIBLE (2025 -700);
FORCEPROP 2 LAST CDS_LIB standard
J 0
(1925 -625);
PAINT MONO (1925 -625);
DISPLAY INVISIBLE (1925 -625);
FORCEADD OFFPAGE..5
(1925 -675);
FORCEPROP 2 LAST $XR0 183 
J 0
(1670 -675);
DISPLAY 0.638298 (1670 -675);
PAINT MONO (1670 -675);
FORCEPROP 1 LAST OFFPAGE TRUE
J 0
(2250 -800);
DISPLAY 0.872340 (2250 -800);
DISPLAY INVISIBLE (2250 -800);
FORCEPROP 1 LAST COMMENT_BODY TRUE
J 0
(2025 -750);
DISPLAY 1.170213 (2025 -750);
PAINT GREEN (2025 -750);
DISPLAY INVISIBLE (2025 -750);
FORCEPROP 2 LAST CDS_LIB standard
J 0
(1925 -675);
PAINT MONO (1925 -675);
DISPLAY INVISIBLE (1925 -675);
FORCEPROP 2 LAST PATH I136
J 0
(1650 -625);
DISPLAY 1.021277 (1650 -625);
DISPLAY INVISIBLE (1650 -625);
FORCEADD Q_RES..1
(3475 -625);
FORCEPROP 1 LAST PART_NUMBER CS22002FB07
J 0
(3325 -550);
DISPLAY 0.638298 (3325 -550);
DISPLAY INVISIBLE (3325 -550);
FORCEPROP 1 LAST TOLERANCE 1%
J 0
(3675 -625);
DISPLAY 0.638298 (3675 -625);
FORCEPROP 1 LAST WATTAGE 1/16W
J 2
(3750 -500);
DISPLAY 0.638298 (3750 -500);
FORCEPROP 1 LAST PACK_TYPE 0402LF
J 0
(3325 -500);
DISPLAY 0.638298 (3325 -500);
FORCEPROP 1 LAST VALUE 2K
J 2
(3650 -625);
DISPLAY 0.638298 (3650 -625);
FORCEPROP 1 LAST MATERIAL CHIP
J 0
(3775 -625);
DISPLAY 0.638298 (3775 -625);
FORCEPROP 1 LAST $LOCATION R1545
J 0
(3200 -625);
DISPLAY 0.787234 (3200 -625);
FORCEPROP 1 LASTPIN (3375 -625) $PN 1
J 0
(3387 -613);
DISPLAY 0.787234 (3387 -613);
FORCEPROP 1 LASTPIN (3575 -625) $PN 2
J 0
(3537 -613);
DISPLAY 0.787234 (3537 -613);
FORCEPROP 2 LAST CDS_LIB pure_quanta
J 0
(3475 -625);
PAINT MONO (3475 -625);
DISPLAY INVISIBLE (3475 -625);
FORCEPROP 1 LAST PATH I137
J 0
(3425 -475);
DISPLAY 0.978723 (3425 -475);
PAINT WHITE (3425 -475);
DISPLAY INVISIBLE (3425 -475);
FORCEPROP 2 LAST CDS_LOCATION R1545
J 0
(3425 -425);
DISPLAY 1.021277 (3425 -425);
DISPLAY INVISIBLE (3425 -425);
FORCEPROP 2 LAST $SEC 1
J 0
(3425 -425);
DISPLAY 0.680851 (3425 -425);
PAINT MONO (3425 -425);
DISPLAY INVISIBLE (3425 -425);
FORCEPROP 2 LAST CDS_SEC 1
J 0
(3425 -425);
DISPLAY 1.021277 (3425 -425);
DISPLAY INVISIBLE (3425 -425);
FORCEADD Q_RES..1
(3475 -675);
FORCEPROP 1 LAST PART_NUMBER CS22002FB07
J 0
(3300 -600);
DISPLAY 0.638298 (3300 -600);
DISPLAY INVISIBLE (3300 -600);
FORCEPROP 1 LAST TOLERANCE 1%
J 0
(3675 -675);
DISPLAY 0.638298 (3675 -675);
FORCEPROP 1 LAST VALUE 2K
J 2
(3650 -675);
DISPLAY 0.638298 (3650 -675);
FORCEPROP 1 LAST MATERIAL CHIP
J 0
(3775 -675);
DISPLAY 0.638298 (3775 -675);
FORCEPROP 1 LAST $LOCATION R1546
J 0
(3200 -675);
DISPLAY 0.787234 (3200 -675);
FORCEPROP 1 LASTPIN (3375 -675) $PN 1
J 0
(3387 -663);
DISPLAY 0.787234 (3387 -663);
FORCEPROP 1 LASTPIN (3575 -675) $PN 2
J 0
(3537 -663);
DISPLAY 0.787234 (3537 -663);
FORCEPROP 2 LAST CDS_LIB pure_quanta
J 0
(3475 -675);
PAINT MONO (3475 -675);
DISPLAY INVISIBLE (3475 -675);
FORCEPROP 1 LAST PATH I138
J 0
(3425 -525);
DISPLAY 0.978723 (3425 -525);
PAINT WHITE (3425 -525);
DISPLAY INVISIBLE (3425 -525);
FORCEPROP 1 LAST WATTAGE 1/16W
J 2
(3725 -550);
DISPLAY 0.638298 (3725 -550);
DISPLAY INVISIBLE (3725 -550);
FORCEPROP 1 LAST PACK_TYPE 0402LF
J 0
(3300 -550);
DISPLAY 0.638298 (3300 -550);
DISPLAY INVISIBLE (3300 -550);
FORCEPROP 2 LAST CDS_LOCATION R1546
J 0
(3425 -475);
DISPLAY 1.021277 (3425 -475);
DISPLAY INVISIBLE (3425 -475);
FORCEPROP 2 LAST $SEC 1
J 0
(3425 -475);
DISPLAY 0.680851 (3425 -475);
PAINT MONO (3425 -475);
DISPLAY INVISIBLE (3425 -475);
FORCEPROP 2 LAST CDS_SEC 1
J 0
(3425 -475);
DISPLAY 1.021277 (3425 -475);
DISPLAY INVISIBLE (3425 -475);
FORCEADD OFFPAGE..5
(1925 -1125);
FORCEPROP 2 LAST $XR0 183 
J 0
(1670 -1125);
DISPLAY 0.638298 (1670 -1125);
PAINT MONO (1670 -1125);
FORCEPROP 1 LAST OFFPAGE TRUE
J 0
(2250 -1250);
DISPLAY 0.872340 (2250 -1250);
DISPLAY INVISIBLE (2250 -1250);
FORCEPROP 1 LAST COMMENT_BODY TRUE
J 0
(2025 -1200);
DISPLAY 1.170213 (2025 -1200);
PAINT GREEN (2025 -1200);
DISPLAY INVISIBLE (2025 -1200);
FORCEPROP 2 LAST CDS_LIB standard
J 0
(1925 -1125);
PAINT MONO (1925 -1125);
DISPLAY INVISIBLE (1925 -1125);
FORCEPROP 2 LAST PATH I139
J 0
(1650 -1075);
DISPLAY 1.021277 (1650 -1075);
DISPLAY INVISIBLE (1650 -1075);
FORCEADD OFFPAGE..5
(1925 -1075);
FORCEPROP 2 LAST $XR0 183 
J 0
(1670 -1075);
DISPLAY 0.638298 (1670 -1075);
PAINT MONO (1670 -1075);
FORCEPROP 2 LAST CDS_LIB standard
J 0
(1925 -1075);
PAINT MONO (1925 -1075);
DISPLAY INVISIBLE (1925 -1075);
FORCEPROP 1 LAST COMMENT_BODY TRUE
J 0
(2025 -1150);
DISPLAY 1.170213 (2025 -1150);
PAINT GREEN (2025 -1150);
DISPLAY INVISIBLE (2025 -1150);
FORCEPROP 1 LAST OFFPAGE TRUE
J 0
(2250 -1200);
DISPLAY 0.872340 (2250 -1200);
DISPLAY INVISIBLE (2250 -1200);
FORCEPROP 2 LAST PATH I140
J 0
(1650 -1025);
DISPLAY 1.021277 (1650 -1025);
DISPLAY INVISIBLE (1650 -1025);
FORCEADD Q_RES..1
(3475 -1125);
FORCEPROP 1 LAST PART_NUMBER CS22002FB07
J 0
(3300 -1050);
DISPLAY 0.638298 (3300 -1050);
DISPLAY INVISIBLE (3300 -1050);
FORCEPROP 1 LAST TOLERANCE 1%
J 0
(3675 -1125);
DISPLAY 0.638298 (3675 -1125);
FORCEPROP 1 LAST MATERIAL CHIP
J 0
(3775 -1125);
DISPLAY 0.638298 (3775 -1125);
FORCEPROP 1 LAST VALUE 2K
J 2
(3650 -1125);
DISPLAY 0.638298 (3650 -1125);
FORCEPROP 1 LAST $LOCATION R1582
J 0
(3200 -1125);
DISPLAY 0.787234 (3200 -1125);
FORCEPROP 1 LASTPIN (3375 -1125) $PN 1
J 0
(3387 -1113);
DISPLAY 0.787234 (3387 -1113);
FORCEPROP 1 LASTPIN (3575 -1125) $PN 2
J 0
(3537 -1113);
DISPLAY 0.787234 (3537 -1113);
FORCEPROP 1 LAST PATH I141
J 0
(3425 -975);
DISPLAY 0.978723 (3425 -975);
PAINT WHITE (3425 -975);
DISPLAY INVISIBLE (3425 -975);
FORCEPROP 1 LAST WATTAGE 1/16W
J 2
(3725 -1000);
DISPLAY 0.638298 (3725 -1000);
DISPLAY INVISIBLE (3725 -1000);
FORCEPROP 1 LAST PACK_TYPE 0402LF
J 0
(3300 -1000);
DISPLAY 0.638298 (3300 -1000);
DISPLAY INVISIBLE (3300 -1000);
FORCEPROP 2 LAST CDS_LIB pure_quanta
J 0
(3475 -1125);
PAINT MONO (3475 -1125);
DISPLAY INVISIBLE (3475 -1125);
FORCEPROP 2 LAST CDS_LOCATION R1582
J 0
(3425 -925);
DISPLAY 1.021277 (3425 -925);
DISPLAY INVISIBLE (3425 -925);
FORCEPROP 2 LAST $SEC 1
J 0
(3425 -925);
DISPLAY 0.680851 (3425 -925);
PAINT MONO (3425 -925);
DISPLAY INVISIBLE (3425 -925);
FORCEPROP 2 LAST CDS_SEC 1
J 0
(3425 -925);
DISPLAY 1.021277 (3425 -925);
DISPLAY INVISIBLE (3425 -925);
FORCEADD Q_RES..1
(3475 -1075);
FORCEPROP 1 LAST PART_NUMBER CS22002FB07
J 0
(3300 -1000);
DISPLAY 0.638298 (3300 -1000);
DISPLAY INVISIBLE (3300 -1000);
FORCEPROP 1 LAST MATERIAL CHIP
J 0
(3775 -1075);
DISPLAY 0.638298 (3775 -1075);
FORCEPROP 1 LAST VALUE 2K
J 2
(3650 -1075);
DISPLAY 0.638298 (3650 -1075);
FORCEPROP 1 LAST TOLERANCE 1%
J 0
(3675 -1075);
DISPLAY 0.638298 (3675 -1075);
FORCEPROP 1 LAST $LOCATION R1581
J 0
(3200 -1075);
DISPLAY 0.787234 (3200 -1075);
FORCEPROP 1 LASTPIN (3375 -1075) $PN 1
J 0
(3387 -1063);
DISPLAY 0.787234 (3387 -1063);
FORCEPROP 1 LASTPIN (3575 -1075) $PN 2
J 0
(3537 -1063);
DISPLAY 0.787234 (3537 -1063);
FORCEPROP 1 LAST WATTAGE 1/16W
J 2
(3725 -950);
DISPLAY 0.638298 (3725 -950);
DISPLAY INVISIBLE (3725 -950);
FORCEPROP 1 LAST PACK_TYPE 0402LF
J 0
(3300 -950);
DISPLAY 0.638298 (3300 -950);
DISPLAY INVISIBLE (3300 -950);
FORCEPROP 2 LAST CDS_LIB pure_quanta
J 0
(3475 -1075);
PAINT MONO (3475 -1075);
DISPLAY INVISIBLE (3475 -1075);
FORCEPROP 1 LAST PATH I142
J 0
(3425 -925);
DISPLAY 0.978723 (3425 -925);
PAINT WHITE (3425 -925);
DISPLAY INVISIBLE (3425 -925);
FORCEPROP 2 LAST CDS_LOCATION R1581
J 0
(3425 -875);
DISPLAY 1.021277 (3425 -875);
DISPLAY INVISIBLE (3425 -875);
FORCEPROP 2 LAST $SEC 1
J 0
(3425 -875);
DISPLAY 0.680851 (3425 -875);
PAINT MONO (3425 -875);
DISPLAY INVISIBLE (3425 -875);
FORCEPROP 2 LAST CDS_SEC 1
J 0
(3425 -875);
DISPLAY 1.021277 (3425 -875);
DISPLAY INVISIBLE (3425 -875);
FORCEADD OFFPAGE..5
(1925 -1175);
FORCEPROP 2 LAST $XR0 183 
J 0
(1670 -1175);
DISPLAY 0.638298 (1670 -1175);
PAINT MONO (1670 -1175);
FORCEPROP 1 LAST OFFPAGE TRUE
J 0
(2250 -1300);
DISPLAY 0.872340 (2250 -1300);
DISPLAY INVISIBLE (2250 -1300);
FORCEPROP 1 LAST COMMENT_BODY TRUE
J 0
(2025 -1250);
DISPLAY 1.170213 (2025 -1250);
PAINT GREEN (2025 -1250);
DISPLAY INVISIBLE (2025 -1250);
FORCEPROP 2 LAST CDS_LIB standard
J 0
(1925 -1175);
PAINT MONO (1925 -1175);
DISPLAY INVISIBLE (1925 -1175);
FORCEPROP 2 LAST PATH I143
J 0
(1650 -1125);
DISPLAY 1.021277 (1650 -1125);
DISPLAY INVISIBLE (1650 -1125);
FORCEADD Q_RES..1
(3475 -1175);
FORCEPROP 1 LAST PART_NUMBER CS31002FB08
J 0
(3325 -1300);
DISPLAY 0.638298 (3325 -1300);
DISPLAY INVISIBLE (3325 -1300);
FORCEPROP 1 LAST TOLERANCE 1%
J 0
(3675 -1175);
DISPLAY 0.638298 (3675 -1175);
FORCEPROP 1 LAST WATTAGE 1/16W
J 2
(3750 -1250);
DISPLAY 0.638298 (3750 -1250);
FORCEPROP 1 LAST PACK_TYPE 0402LF
J 0
(3325 -1250);
DISPLAY 0.638298 (3325 -1250);
FORCEPROP 1 LAST MATERIAL CHIP
J 0
(3775 -1175);
DISPLAY 0.638298 (3775 -1175);
FORCEPROP 1 LAST VALUE 10K
J 2
(3650 -1175);
DISPLAY 0.638298 (3650 -1175);
FORCEPROP 1 LAST $LOCATION R1583
J 0
(3200 -1175);
DISPLAY 0.787234 (3200 -1175);
FORCEPROP 1 LAST PATH I144
J 0
(3425 -1025);
DISPLAY 0.978723 (3425 -1025);
PAINT WHITE (3425 -1025);
DISPLAY INVISIBLE (3425 -1025);
FORCEPROP 2 LAST CDS_LIB pure_quanta
J 0
(3475 -1175);
PAINT MONO (3475 -1175);
DISPLAY INVISIBLE (3475 -1175);
FORCEPROP 2 LAST CDS_LOCATION R1583
J 0
(3425 -975);
DISPLAY 1.021277 (3425 -975);
DISPLAY INVISIBLE (3425 -975);
FORCEPROP 2 LAST $SEC 1
J 0
(3425 -975);
DISPLAY 0.680851 (3425 -975);
PAINT MONO (3425 -975);
DISPLAY INVISIBLE (3425 -975);
FORCEPROP 2 LAST CDS_SEC 1
J 0
(3425 -975);
DISPLAY 1.021277 (3425 -975);
DISPLAY INVISIBLE (3425 -975);
FORCEPROP 1 LASTPIN (3375 -1175) $PN 1
J 0
(3387 -1163);
DISPLAY 0.787234 (3387 -1163);
DISPLAY INVISIBLE (3387 -1163);
FORCEPROP 1 LASTPIN (3575 -1175) $PN 2
J 0
(3537 -1163);
DISPLAY 0.787234 (3537 -1163);
DISPLAY INVISIBLE (3537 -1163);
FORCEADD OFFPAGE..2
(4500 1275);
FORCEPROP 2 LAST $XR1 228 
J 0
(4809 1275);
DISPLAY 0.638298 (4809 1275);
PAINT MONO (4809 1275);
FORCEPROP 2 LAST $XR0 213 
J 0
(4689 1275);
DISPLAY 0.638298 (4689 1275);
PAINT MONO (4689 1275);
FORCEPROP 1 LAST COMMENT_BODY TRUE
J 0
(4455 1180);
DISPLAY 0.872340 (4455 1180);
PAINT GREEN (4455 1180);
DISPLAY INVISIBLE (4455 1180);
FORCEPROP 1 LAST OFFPAGE TRUE
J 0
(4825 1150);
DISPLAY 0.872340 (4825 1150);
DISPLAY INVISIBLE (4825 1150);
FORCEPROP 2 LAST PATH I145
J 0
(4700 1325);
DISPLAY 1.021277 (4700 1325);
DISPLAY INVISIBLE (4700 1325);
FORCEPROP 2 LAST CDS_LIB standard
J 0
(4500 1275);
DISPLAY INVISIBLE (4500 1275);
FORCEADD OFFPAGE..1
(1600 1275);
FORCEPROP 2 LAST $XR0 183 
J 0
(1348 1275);
DISPLAY 0.638298 (1348 1275);
PAINT MONO (1348 1275);
FORCEPROP 1 LAST OFFPAGE TRUE
J 0
(1925 1150);
DISPLAY 0.872340 (1925 1150);
DISPLAY INVISIBLE (1925 1150);
FORCEPROP 1 LAST COMMENT_BODY TRUE
J 0
(1725 1175);
DISPLAY 0.872340 (1725 1175);
PAINT GREEN (1725 1175);
DISPLAY INVISIBLE (1725 1175);
FORCEPROP 2 LAST PATH I147
J 0
(1325 1325);
DISPLAY 1.021277 (1325 1325);
DISPLAY INVISIBLE (1325 1325);
FORCEPROP 2 LAST CDS_LIB standard
J 0
(1600 1275);
DISPLAY INVISIBLE (1600 1275);
FORCEADD Q_RES..1
(2950 1275);
FORCEPROP 1 LAST PART_NUMBER CS03322FB03
J 0
(2850 1350);
DISPLAY 0.404255 (2850 1350);
DISPLAY INVISIBLE (2850 1350);
FORCEPROP 1 LAST MATERIAL CHIP
J 0
(3250 1275);
DISPLAY 0.510638 (3250 1275);
FORCEPROP 1 LAST TOLERANCE 1%
J 0
(3175 1275);
DISPLAY 0.510638 (3175 1275);
FORCEPROP 1 LAST WATTAGE 1/16W
J 2
(3100 1375);
DISPLAY 0.404255 (3100 1375);
FORCEPROP 1 LAST VALUE 33.2
J 2
(3150 1275);
DISPLAY 0.510638 (3150 1275);
FORCEPROP 1 LAST PACK_TYPE 0402LF
J 0
(2850 1375);
DISPLAY 0.404255 (2850 1375);
FORCEPROP 1 LAST $LOCATION R1600
J 0
(2700 1275);
DISPLAY 0.638298 (2700 1275);
FORCEPROP 1 LASTPIN (2850 1275) $PN 1
J 0
(2862 1287);
DISPLAY 0.787234 (2862 1287);
FORCEPROP 1 LASTPIN (3050 1275) $PN 2
J 0
(3012 1287);
DISPLAY 0.787234 (3012 1287);
FORCEPROP 1 LAST PATH I148
J 0
(2900 1425);
DISPLAY 0.978723 (2900 1425);
PAINT WHITE (2900 1425);
DISPLAY INVISIBLE (2900 1425);
FORCEPROP 2 LAST CDS_LIB pure_quanta
J 0
(2950 1275);
PAINT MONO (2950 1275);
DISPLAY INVISIBLE (2950 1275);
FORCEPROP 2 LAST CDS_LOCATION R1600
J 0
(2900 1475);
DISPLAY 1.021277 (2900 1475);
DISPLAY INVISIBLE (2900 1475);
FORCEPROP 2 LAST $SEC 1
J 0
(2900 1475);
DISPLAY 0.680851 (2900 1475);
PAINT MONO (2900 1475);
DISPLAY INVISIBLE (2900 1475);
FORCEPROP 2 LAST CDS_SEC 1
J 0
(2900 1475);
DISPLAY 1.021277 (2900 1475);
DISPLAY INVISIBLE (2900 1475);
FORCEADD OFFPAGE..5
(-1925 3250);
FORCEPROP 2 LAST $XR0 131 
J 0
(-2180 3250);
DISPLAY 0.638298 (-2180 3250);
PAINT MONO (-2180 3250);
FORCEPROP 2 LAST PATH I15
J 0
(-1875 3325);
DISPLAY 1.021277 (-1875 3325);
DISPLAY INVISIBLE (-1875 3325);
FORCEPROP 2 LAST CDS_LIB standard
J 0
(-1925 3250);
PAINT MONO (-1925 3250);
DISPLAY INVISIBLE (-1925 3250);
FORCEPROP 1 LAST OFFPAGE TRUE
J 0
(-1600 3125);
DISPLAY 0.872340 (-1600 3125);
DISPLAY INVISIBLE (-1600 3125);
FORCEPROP 1 LAST COMMENT_BODY TRUE
J 0
(-1825 3175);
DISPLAY 1.170213 (-1825 3175);
PAINT GREEN (-1825 3175);
DISPLAY INVISIBLE (-1825 3175);
FORCEADD OFFPAGE..5
(1925 -25);
FORCEPROP 2 LAST $XR0 183 
J 0
(1670 -25);
DISPLAY 0.638298 (1670 -25);
PAINT MONO (1670 -25);
FORCEPROP 2 LAST PATH I150
J 0
(1625 25);
DISPLAY 1.021277 (1625 25);
DISPLAY INVISIBLE (1625 25);
FORCEPROP 1 LAST OFFPAGE TRUE
J 0
(2250 -150);
DISPLAY 0.872340 (2250 -150);
DISPLAY INVISIBLE (2250 -150);
FORCEPROP 1 LAST COMMENT_BODY TRUE
J 0
(2025 -100);
DISPLAY 1.170213 (2025 -100);
PAINT GREEN (2025 -100);
DISPLAY INVISIBLE (2025 -100);
FORCEPROP 2 LAST CDS_LIB standard
J 0
(1925 -25);
PAINT MONO (1925 -25);
DISPLAY INVISIBLE (1925 -25);
FORCEADD Q_RES..1
(3475 -25);
FORCEPROP 1 LAST PART_NUMBER CS31002FB08
J 0
(3325 50);
DISPLAY 0.638298 (3325 50);
DISPLAY INVISIBLE (3325 50);
FORCEPROP 1 LAST WATTAGE 1/16W
J 2
(3725 100);
DISPLAY 0.638298 (3725 100);
FORCEPROP 1 LAST PACK_TYPE 0402LF
J 0
(3325 100);
DISPLAY 0.638298 (3325 100);
FORCEPROP 1 LAST VALUE 10K
J 2
(3675 -25);
DISPLAY 0.638298 (3675 -25);
FORCEPROP 1 LAST TOLERANCE 1%
J 0
(3700 -25);
DISPLAY 0.638298 (3700 -25);
FORCEPROP 1 LAST MATERIAL CHIP
J 0
(3800 -25);
DISPLAY 0.638298 (3800 -25);
FORCEPROP 1 LAST $LOCATION R1601
J 0
(3200 -25);
DISPLAY 0.638298 (3200 -25);
FORCEPROP 1 LASTPIN (3375 -25) $PN 1
J 0
(3387 -13);
DISPLAY 0.787234 (3387 -13);
FORCEPROP 1 LASTPIN (3575 -25) $PN 2
J 0
(3537 -13);
DISPLAY 0.787234 (3537 -13);
FORCEPROP 1 LAST PATH I151
J 0
(3425 125);
DISPLAY 0.978723 (3425 125);
PAINT WHITE (3425 125);
DISPLAY INVISIBLE (3425 125);
FORCEPROP 2 LAST CDS_LIB pure_quanta
J 0
(3475 -25);
PAINT MONO (3475 -25);
DISPLAY INVISIBLE (3475 -25);
FORCEPROP 2 LAST CDS_LOCATION R1601
J 0
(3425 175);
DISPLAY 1.021277 (3425 175);
DISPLAY INVISIBLE (3425 175);
FORCEPROP 2 LAST $SEC 1
J 0
(3425 175);
DISPLAY 0.680851 (3425 175);
PAINT MONO (3425 175);
DISPLAY INVISIBLE (3425 175);
FORCEPROP 2 LAST CDS_SEC 1
J 0
(3425 175);
DISPLAY 1.021277 (3425 175);
DISPLAY INVISIBLE (3425 175);
FORCEADD OFFPAGE..5
(-1925 3200);
FORCEPROP 2 LAST $XR0 131 
J 0
(-2180 3200);
DISPLAY 0.638298 (-2180 3200);
PAINT MONO (-2180 3200);
FORCEPROP 2 LAST PATH I16
J 0
(-1875 3275);
DISPLAY 1.021277 (-1875 3275);
DISPLAY INVISIBLE (-1875 3275);
FORCEPROP 2 LAST CDS_LIB standard
J 0
(-1925 3200);
PAINT MONO (-1925 3200);
DISPLAY INVISIBLE (-1925 3200);
FORCEPROP 1 LAST OFFPAGE TRUE
J 0
(-1600 3075);
DISPLAY 0.872340 (-1600 3075);
DISPLAY INVISIBLE (-1600 3075);
FORCEPROP 1 LAST COMMENT_BODY TRUE
J 0
(-1825 3125);
DISPLAY 1.170213 (-1825 3125);
PAINT GREEN (-1825 3125);
DISPLAY INVISIBLE (-1825 3125);
FORCEADD OFFPAGE..5
(-1925 3150);
FORCEPROP 2 LAST $XR0 131 
J 0
(-2180 3150);
DISPLAY 0.638298 (-2180 3150);
PAINT MONO (-2180 3150);
FORCEPROP 2 LAST PATH I17
J 0
(-1875 3225);
DISPLAY 1.021277 (-1875 3225);
DISPLAY INVISIBLE (-1875 3225);
FORCEPROP 2 LAST CDS_LIB standard
J 0
(-1925 3150);
PAINT MONO (-1925 3150);
DISPLAY INVISIBLE (-1925 3150);
FORCEPROP 1 LAST OFFPAGE TRUE
J 0
(-1600 3025);
DISPLAY 0.872340 (-1600 3025);
DISPLAY INVISIBLE (-1600 3025);
FORCEPROP 1 LAST COMMENT_BODY TRUE
J 0
(-1825 3075);
DISPLAY 1.170213 (-1825 3075);
PAINT GREEN (-1825 3075);
DISPLAY INVISIBLE (-1825 3075);
FORCEADD OFFPAGE..1
(1600 1150);
FORCEPROP 2 LAST $XR4 215 
J 0
(868 1150);
DISPLAY 0.638298 (868 1150);
PAINT MONO (868 1150);
FORCEPROP 2 LAST $XR3 183 
J 0
(988 1150);
DISPLAY 0.638298 (988 1150);
PAINT MONO (988 1150);
FORCEPROP 2 LAST $XR2 305 
J 0
(1108 1150);
DISPLAY 0.638298 (1108 1150);
PAINT MONO (1108 1150);
FORCEPROP 2 LAST $XR1 301 
J 0
(1228 1150);
DISPLAY 0.638298 (1228 1150);
PAINT MONO (1228 1150);
FORCEPROP 2 LAST $XR0 228 
J 0
(1348 1150);
DISPLAY 0.638298 (1348 1150);
PAINT MONO (1348 1150);
FORCEPROP 2 LAST PATH I175
J 0
(1325 1200);
DISPLAY 1.021277 (1325 1200);
DISPLAY INVISIBLE (1325 1200);
FORCEPROP 2 LAST CDS_LIB standard
J 0
(1600 1150);
DISPLAY INVISIBLE (1600 1150);
FORCEPROP 1 LAST OFFPAGE TRUE
J 0
(1925 1025);
DISPLAY 0.872340 (1925 1025);
DISPLAY INVISIBLE (1925 1025);
FORCEPROP 1 LAST COMMENT_BODY TRUE
J 0
(1725 1050);
DISPLAY 0.872340 (1725 1050);
PAINT GREEN (1725 1050);
DISPLAY INVISIBLE (1725 1050);
FORCEADD OFFPAGE..2
(4500 1150);
FORCEPROP 2 LAST $XR0 213 
J 0
(4689 1150);
DISPLAY 0.638298 (4689 1150);
PAINT MONO (4689 1150);
FORCEPROP 1 LAST OFFPAGE TRUE
J 0
(4825 1025);
DISPLAY 0.872340 (4825 1025);
DISPLAY INVISIBLE (4825 1025);
FORCEPROP 1 LAST COMMENT_BODY TRUE
J 0
(4455 1055);
DISPLAY 0.872340 (4455 1055);
PAINT GREEN (4455 1055);
DISPLAY INVISIBLE (4455 1055);
FORCEPROP 2 LAST PATH I177
J 0
(4700 1200);
DISPLAY 1.021277 (4700 1200);
DISPLAY INVISIBLE (4700 1200);
FORCEPROP 2 LAST CDS_LIB standard
J 0
(4500 1150);
DISPLAY INVISIBLE (4500 1150);
FORCEADD Q_RES..1
(2950 1150);
FORCEPROP 1 LAST PART_NUMBER CS03322FB03
J 0
(2850 1200);
DISPLAY 0.510638 (2850 1200);
DISPLAY INVISIBLE (2850 1200);
FORCEPROP 1 LAST VALUE 33.2
J 2
(3150 1150);
DISPLAY 0.510638 (3150 1150);
FORCEPROP 1 LAST MATERIAL CHIP
J 0
(3250 1150);
DISPLAY 0.510638 (3250 1150);
FORCEPROP 1 LAST TOLERANCE 1%
J 0
(3175 1150);
DISPLAY 0.510638 (3175 1150);
FORCEPROP 1 LAST $LOCATION R1656
J 0
(2700 1150);
DISPLAY 0.638298 (2700 1150);
FORCEPROP 1 LASTPIN (2850 1150) $PN 1
J 0
(2862 1162);
DISPLAY 0.787234 (2862 1162);
FORCEPROP 1 LASTPIN (3050 1150) $PN 2
J 0
(3012 1162);
DISPLAY 0.787234 (3012 1162);
FORCEPROP 1 LAST WATTAGE 1/16W
J 2
(3150 1250);
DISPLAY 0.510638 (3150 1250);
DISPLAY INVISIBLE (3150 1250);
FORCEPROP 1 LAST PACK_TYPE 0402LF
J 0
(2850 1250);
DISPLAY 0.510638 (2850 1250);
DISPLAY INVISIBLE (2850 1250);
FORCEPROP 2 LAST CDS_LIB pure_quanta
J 0
(2950 1150);
PAINT MONO (2950 1150);
DISPLAY INVISIBLE (2950 1150);
FORCEPROP 1 LAST PATH I178
J 0
(2900 1300);
DISPLAY 0.978723 (2900 1300);
PAINT WHITE (2900 1300);
DISPLAY INVISIBLE (2900 1300);
FORCEPROP 2 LAST CDS_LOCATION R1656
J 0
(2900 1350);
DISPLAY 1.021277 (2900 1350);
DISPLAY INVISIBLE (2900 1350);
FORCEPROP 2 LAST $SEC 1
J 0
(2900 1350);
DISPLAY 0.680851 (2900 1350);
PAINT MONO (2900 1350);
DISPLAY INVISIBLE (2900 1350);
FORCEPROP 2 LAST CDS_SEC 1
J 0
(2900 1350);
DISPLAY 1.021277 (2900 1350);
DISPLAY INVISIBLE (2900 1350);
FORCEADD OFFPAGE..5
(-1925 3100);
FORCEPROP 2 LAST $XR0 131 
J 0
(-2180 3100);
DISPLAY 0.638298 (-2180 3100);
PAINT MONO (-2180 3100);
FORCEPROP 2 LAST PATH I18
J 0
(-1875 3175);
DISPLAY 1.021277 (-1875 3175);
DISPLAY INVISIBLE (-1875 3175);
FORCEPROP 1 LAST COMMENT_BODY TRUE
J 0
(-1825 3025);
DISPLAY 1.170213 (-1825 3025);
PAINT GREEN (-1825 3025);
DISPLAY INVISIBLE (-1825 3025);
FORCEPROP 1 LAST OFFPAGE TRUE
J 0
(-1600 2975);
DISPLAY 0.872340 (-1600 2975);
DISPLAY INVISIBLE (-1600 2975);
FORCEPROP 2 LAST CDS_LIB standard
J 0
(-1925 3100);
PAINT MONO (-1925 3100);
DISPLAY INVISIBLE (-1925 3100);
FORCEADD Q_RES..1
(2950 1025);
FORCEPROP 1 LAST PART_NUMBER CS03322FB03
J 0
(2850 1075);
DISPLAY 0.510638 (2850 1075);
DISPLAY INVISIBLE (2850 1075);
FORCEPROP 1 LAST MATERIAL CHIP
J 0
(3250 1025);
DISPLAY 0.510638 (3250 1025);
FORCEPROP 1 LAST TOLERANCE 1%
J 0
(3175 1025);
DISPLAY 0.510638 (3175 1025);
FORCEPROP 1 LAST VALUE 33.2
J 2
(3150 1025);
DISPLAY 0.510638 (3150 1025);
FORCEPROP 1 LAST $LOCATION R1657
J 0
(2700 1025);
DISPLAY 0.638298 (2700 1025);
FORCEPROP 1 LASTPIN (2850 1025) $PN 1
J 0
(2862 1037);
DISPLAY 0.787234 (2862 1037);
FORCEPROP 1 LASTPIN (3050 1025) $PN 2
J 0
(3012 1037);
DISPLAY 0.787234 (3012 1037);
FORCEPROP 1 LAST WATTAGE 1/16W
J 2
(3150 1125);
DISPLAY 0.510638 (3150 1125);
DISPLAY INVISIBLE (3150 1125);
FORCEPROP 1 LAST PACK_TYPE 0402LF
J 0
(2850 1125);
DISPLAY 0.510638 (2850 1125);
DISPLAY INVISIBLE (2850 1125);
FORCEPROP 1 LAST PATH I180
J 0
(2900 1175);
DISPLAY 0.978723 (2900 1175);
PAINT WHITE (2900 1175);
DISPLAY INVISIBLE (2900 1175);
FORCEPROP 2 LAST CDS_LIB pure_quanta
J 0
(2950 1025);
PAINT MONO (2950 1025);
DISPLAY INVISIBLE (2950 1025);
FORCEPROP 2 LAST CDS_LOCATION R1657
J 0
(2900 1225);
DISPLAY 1.021277 (2900 1225);
DISPLAY INVISIBLE (2900 1225);
FORCEPROP 2 LAST $SEC 1
J 0
(2900 1225);
DISPLAY 0.680851 (2900 1225);
PAINT MONO (2900 1225);
DISPLAY INVISIBLE (2900 1225);
FORCEPROP 2 LAST CDS_SEC 1
J 0
(2900 1225);
DISPLAY 1.021277 (2900 1225);
DISPLAY INVISIBLE (2900 1225);
FORCEADD Q_RES..1
(3475 -125);
FORCEPROP 1 LAST PART_NUMBER CS31002FB08
J 0
(3325 -50);
DISPLAY 0.638298 (3325 -50);
DISPLAY INVISIBLE (3325 -50);
FORCEPROP 1 LAST VALUE 10K
J 2
(3675 -125);
DISPLAY 0.638298 (3675 -125);
FORCEPROP 1 LAST TOLERANCE 1%
J 0
(3700 -125);
DISPLAY 0.638298 (3700 -125);
FORCEPROP 1 LAST MATERIAL CHIP
J 0
(3800 -125);
DISPLAY 0.638298 (3800 -125);
FORCEPROP 1 LAST $LOCATION R1659
J 0
(3200 -125);
DISPLAY 0.638298 (3200 -125);
FORCEPROP 1 LASTPIN (3375 -125) $PN 1
J 0
(3387 -113);
DISPLAY 0.787234 (3387 -113);
FORCEPROP 1 LASTPIN (3575 -125) $PN 2
J 0
(3537 -113);
DISPLAY 0.787234 (3537 -113);
FORCEPROP 2 LAST CDS_LIB pure_quanta
J 0
(3475 -125);
PAINT MONO (3475 -125);
DISPLAY INVISIBLE (3475 -125);
FORCEPROP 1 LAST PATH I181
J 0
(3425 25);
DISPLAY 0.978723 (3425 25);
PAINT WHITE (3425 25);
DISPLAY INVISIBLE (3425 25);
FORCEPROP 1 LAST WATTAGE 1/16W
J 2
(3725 0);
DISPLAY 0.638298 (3725 0);
DISPLAY INVISIBLE (3725 0);
FORCEPROP 1 LAST PACK_TYPE 0402LF
J 0
(3325 0);
DISPLAY 0.638298 (3325 0);
DISPLAY INVISIBLE (3325 0);
FORCEPROP 2 LAST CDS_LOCATION R1659
J 0
(3425 75);
DISPLAY 1.021277 (3425 75);
DISPLAY INVISIBLE (3425 75);
FORCEPROP 2 LAST $SEC 1
J 0
(3425 75);
DISPLAY 0.680851 (3425 75);
PAINT MONO (3425 75);
DISPLAY INVISIBLE (3425 75);
FORCEPROP 2 LAST CDS_SEC 1
J 0
(3425 75);
DISPLAY 1.021277 (3425 75);
DISPLAY INVISIBLE (3425 75);
FORCEADD OFFPAGE..5
(1925 -125);
FORCEPROP 2 LAST $XR0 183 
J 0
(1670 -125);
DISPLAY 0.638298 (1670 -125);
PAINT MONO (1670 -125);
FORCEPROP 2 LAST PATH I182
J 0
(1650 -75);
DISPLAY 1.021277 (1650 -75);
DISPLAY INVISIBLE (1650 -75);
FORCEPROP 2 LAST CDS_LIB standard
J 0
(1925 -125);
PAINT MONO (1925 -125);
DISPLAY INVISIBLE (1925 -125);
FORCEPROP 1 LAST COMMENT_BODY TRUE
J 0
(2025 -200);
DISPLAY 1.170213 (2025 -200);
PAINT GREEN (2025 -200);
DISPLAY INVISIBLE (2025 -200);
FORCEPROP 1 LAST OFFPAGE TRUE
J 0
(2250 -250);
DISPLAY 0.872340 (2250 -250);
DISPLAY INVISIBLE (2250 -250);
FORCEADD OFFPAGE..2
(4450 3950);
FORCEPROP 2 LAST $XR1 205 
J 0
(4759 3950);
DISPLAY 0.638298 (4759 3950);
PAINT MONO (4759 3950);
FORCEPROP 2 LAST $XR0 204 
J 0
(4639 3950);
DISPLAY 0.638298 (4639 3950);
PAINT MONO (4639 3950);
FORCEPROP 2 LAST CDS_LIB standard
J 0
(4450 3950);
PAINT MONO (4450 3950);
DISPLAY INVISIBLE (4450 3950);
FORCEPROP 2 LAST PATH I183
J 0
(4800 4000);
DISPLAY 1.021277 (4800 4000);
DISPLAY INVISIBLE (4800 4000);
FORCEPROP 1 LAST COMMENT_BODY TRUE
J 0
(4405 3855);
DISPLAY 0.872340 (4405 3855);
PAINT GREEN (4405 3855);
DISPLAY INVISIBLE (4405 3855);
FORCEPROP 1 LAST OFFPAGE TRUE
J 0
(4775 3825);
DISPLAY 0.872340 (4775 3825);
PAINT GREEN (4775 3825);
DISPLAY INVISIBLE (4775 3825);
FORCEADD Q_RES..1
(3475 -175);
FORCEPROP 1 LAST PART_NUMBER CS31002FB08
J 0
(3325 -100);
DISPLAY 0.638298 (3325 -100);
DISPLAY INVISIBLE (3325 -100);
FORCEPROP 1 LAST TOLERANCE 1%
J 0
(3700 -175);
DISPLAY 0.638298 (3700 -175);
FORCEPROP 1 LAST MATERIAL CHIP
J 0
(3800 -175);
DISPLAY 0.638298 (3800 -175);
FORCEPROP 1 LAST VALUE 10K
J 2
(3675 -175);
DISPLAY 0.638298 (3675 -175);
FORCEPROP 1 LAST $LOCATION R1828
J 0
(3200 -175);
DISPLAY 0.638298 (3200 -175);
FORCEPROP 1 LASTPIN (3375 -175) $PN 1
J 0
(3387 -163);
DISPLAY 0.787234 (3387 -163);
FORCEPROP 1 LASTPIN (3575 -175) $PN 2
J 0
(3537 -163);
DISPLAY 0.787234 (3537 -163);
FORCEPROP 2 LAST CDS_LIB pure_quanta
J 0
(3475 -175);
PAINT MONO (3475 -175);
DISPLAY INVISIBLE (3475 -175);
FORCEPROP 1 LAST PATH I188
J 0
(3425 -25);
DISPLAY 0.978723 (3425 -25);
PAINT WHITE (3425 -25);
DISPLAY INVISIBLE (3425 -25);
FORCEPROP 1 LAST PACK_TYPE 0402LF
J 0
(3325 -50);
DISPLAY 0.638298 (3325 -50);
DISPLAY INVISIBLE (3325 -50);
FORCEPROP 1 LAST WATTAGE 1/16W
J 2
(3725 -50);
DISPLAY 0.638298 (3725 -50);
DISPLAY INVISIBLE (3725 -50);
FORCEPROP 2 LAST CDS_LOCATION R1828
J 0
(3425 25);
DISPLAY 1.021277 (3425 25);
DISPLAY INVISIBLE (3425 25);
FORCEPROP 2 LAST $SEC 1
J 0
(3425 25);
DISPLAY 0.680851 (3425 25);
PAINT MONO (3425 25);
DISPLAY INVISIBLE (3425 25);
FORCEPROP 2 LAST CDS_SEC 1
J 0
(3425 25);
DISPLAY 1.021277 (3425 25);
DISPLAY INVISIBLE (3425 25);
FORCEADD OFFPAGE..5
(1925 -175);
FORCEPROP 2 LAST $XR0 183 
J 0
(1670 -175);
DISPLAY 0.638298 (1670 -175);
PAINT MONO (1670 -175);
FORCEPROP 1 LAST COMMENT_BODY TRUE
J 0
(2025 -250);
DISPLAY 1.170213 (2025 -250);
PAINT GREEN (2025 -250);
DISPLAY INVISIBLE (2025 -250);
FORCEPROP 1 LAST OFFPAGE TRUE
J 0
(2250 -300);
DISPLAY 0.872340 (2250 -300);
DISPLAY INVISIBLE (2250 -300);
FORCEPROP 2 LAST PATH I189
J 0
(1650 -125);
DISPLAY 1.021277 (1650 -125);
DISPLAY INVISIBLE (1650 -125);
FORCEPROP 2 LAST CDS_LIB standard
J 0
(1925 -175);
PAINT MONO (1925 -175);
DISPLAY INVISIBLE (1925 -175);
FORCEADD OFFPAGE..5
(-1925 3050);
FORCEPROP 2 LAST $XR0 131 
J 0
(-2180 3050);
DISPLAY 0.638298 (-2180 3050);
PAINT MONO (-2180 3050);
FORCEPROP 2 LAST PATH I19
J 0
(-1875 3125);
DISPLAY 1.021277 (-1875 3125);
DISPLAY INVISIBLE (-1875 3125);
FORCEPROP 1 LAST COMMENT_BODY TRUE
J 0
(-1825 2975);
DISPLAY 1.170213 (-1825 2975);
PAINT GREEN (-1825 2975);
DISPLAY INVISIBLE (-1825 2975);
FORCEPROP 1 LAST OFFPAGE TRUE
J 0
(-1600 2925);
DISPLAY 0.872340 (-1600 2925);
DISPLAY INVISIBLE (-1600 2925);
FORCEPROP 2 LAST CDS_LIB standard
J 0
(-1925 3050);
PAINT MONO (-1925 3050);
DISPLAY INVISIBLE (-1925 3050);
FORCEADD Q_RES..1
(2950 775);
FORCEPROP 1 LAST PART_NUMBER CS03322FB03
J 0
(2850 825);
DISPLAY 0.510638 (2850 825);
DISPLAY INVISIBLE (2850 825);
FORCEPROP 1 LAST MATERIAL CHIP
J 0
(3250 775);
DISPLAY 0.510638 (3250 775);
FORCEPROP 1 LAST TOLERANCE 1%
J 0
(3175 775);
DISPLAY 0.510638 (3175 775);
FORCEPROP 1 LAST VALUE 33.2
J 2
(3150 775);
DISPLAY 0.510638 (3150 775);
FORCEPROP 1 LAST $LOCATION R1827
J 0
(2700 775);
DISPLAY 0.638298 (2700 775);
FORCEPROP 1 LASTPIN (2850 775) $PN 1
J 0
(2862 787);
DISPLAY 0.787234 (2862 787);
FORCEPROP 1 LASTPIN (3050 775) $PN 2
J 0
(3012 787);
DISPLAY 0.787234 (3012 787);
FORCEPROP 1 LAST WATTAGE 1/16W
J 2
(3150 875);
DISPLAY 0.510638 (3150 875);
DISPLAY INVISIBLE (3150 875);
FORCEPROP 1 LAST PACK_TYPE 0402LF
J 0
(2850 875);
DISPLAY 0.510638 (2850 875);
DISPLAY INVISIBLE (2850 875);
FORCEPROP 2 LAST CDS_LIB pure_quanta
J 0
(2950 775);
PAINT MONO (2950 775);
DISPLAY INVISIBLE (2950 775);
FORCEPROP 1 LAST PATH I193
J 0
(2900 925);
DISPLAY 0.978723 (2900 925);
PAINT WHITE (2900 925);
DISPLAY INVISIBLE (2900 925);
FORCEPROP 2 LAST CDS_LOCATION R1827
J 0
(2900 975);
DISPLAY 1.021277 (2900 975);
DISPLAY INVISIBLE (2900 975);
FORCEPROP 2 LAST $SEC 1
J 0
(2900 975);
DISPLAY 0.680851 (2900 975);
PAINT MONO (2900 975);
DISPLAY INVISIBLE (2900 975);
FORCEPROP 2 LAST CDS_SEC 1
J 0
(2900 975);
DISPLAY 1.021277 (2900 975);
DISPLAY INVISIBLE (2900 975);
FORCEADD OFFPAGE..1
R 2
(4500 775);
FORCEPROP 2 LAST $XR0 215 
J 0
(4686 775);
DISPLAY 0.638298 (4686 775);
PAINT MONO (4686 775);
FORCEPROP 2 LAST CDS_LIB standard
J 0
(4500 775);
PAINT MONO (4500 775);
DISPLAY INVISIBLE (4500 775);
FORCEPROP 2 LAST PATH I194
J 0
(4700 825);
DISPLAY 1.021277 (4700 825);
DISPLAY INVISIBLE (4700 825);
FORCEPROP 1 LAST OFFPAGE TRUE
J 2
(4175 650);
DISPLAY 0.872340 (4175 650);
DISPLAY INVISIBLE (4175 650);
FORCEPROP 1 LAST COMMENT_BODY TRUE
J 2
(4375 675);
DISPLAY 0.872340 (4375 675);
PAINT GREEN (4375 675);
DISPLAY INVISIBLE (4375 675);
FORCEADD OFFPAGE..5
(1600 775);
FORCEPROP 2 LAST $XR0 183 
J 0
(1345 775);
DISPLAY 0.638298 (1345 775);
PAINT MONO (1345 775);
FORCEPROP 2 LAST CDS_LIB standard
J 0
(1600 775);
PAINT MONO (1600 775);
DISPLAY INVISIBLE (1600 775);
FORCEPROP 2 LAST PATH I195
J 0
(1325 825);
DISPLAY 1.021277 (1325 825);
DISPLAY INVISIBLE (1325 825);
FORCEPROP 1 LAST COMMENT_BODY TRUE
J 0
(1700 700);
DISPLAY 1.170213 (1700 700);
PAINT GREEN (1700 700);
DISPLAY INVISIBLE (1700 700);
FORCEPROP 1 LAST OFFPAGE TRUE
J 0
(1925 650);
DISPLAY 0.872340 (1925 650);
DISPLAY INVISIBLE (1925 650);
FORCEADD OFFPAGE..5
(-1925 3000);
FORCEPROP 2 LAST $XR0 131 
J 0
(-2180 3000);
DISPLAY 0.638298 (-2180 3000);
PAINT MONO (-2180 3000);
FORCEPROP 2 LAST PATH I20
J 0
(-1875 3075);
DISPLAY 1.021277 (-1875 3075);
DISPLAY INVISIBLE (-1875 3075);
FORCEPROP 1 LAST COMMENT_BODY TRUE
J 0
(-1825 2925);
DISPLAY 1.170213 (-1825 2925);
PAINT GREEN (-1825 2925);
DISPLAY INVISIBLE (-1825 2925);
FORCEPROP 1 LAST OFFPAGE TRUE
J 0
(-1600 2875);
DISPLAY 0.872340 (-1600 2875);
DISPLAY INVISIBLE (-1600 2875);
FORCEPROP 2 LAST CDS_LIB standard
J 0
(-1925 3000);
PAINT MONO (-1925 3000);
DISPLAY INVISIBLE (-1925 3000);
FORCEADD OFFPAGE..2
(4450 2600);
FORCEPROP 2 LAST $XR1 183 
J 0
(4759 2600);
DISPLAY 0.638298 (4759 2600);
PAINT MONO (4759 2600);
FORCEPROP 2 LAST $XR0 204 
J 0
(4639 2600);
DISPLAY 0.638298 (4639 2600);
PAINT MONO (4639 2600);
FORCEPROP 1 LAST OFFPAGE TRUE
J 0
(4775 2475);
DISPLAY 0.872340 (4775 2475);
PAINT GREEN (4775 2475);
DISPLAY INVISIBLE (4775 2475);
FORCEPROP 1 LAST COMMENT_BODY TRUE
J 0
(4405 2505);
DISPLAY 0.872340 (4405 2505);
PAINT GREEN (4405 2505);
DISPLAY INVISIBLE (4405 2505);
FORCEPROP 2 LAST PATH I209
J 0
(4800 2650);
DISPLAY 1.021277 (4800 2650);
DISPLAY INVISIBLE (4800 2650);
FORCEPROP 2 LAST CDS_LIB standard
J 0
(4450 2600);
DISPLAY INVISIBLE (4450 2600);
FORCEADD OFFPAGE..5
(-1925 2950);
FORCEPROP 2 LAST $XR0 131 
J 0
(-2180 2950);
DISPLAY 0.638298 (-2180 2950);
PAINT MONO (-2180 2950);
FORCEPROP 2 LAST PATH I21
J 0
(-1875 3025);
DISPLAY 1.021277 (-1875 3025);
DISPLAY INVISIBLE (-1875 3025);
FORCEPROP 1 LAST COMMENT_BODY TRUE
J 0
(-1825 2875);
DISPLAY 1.170213 (-1825 2875);
PAINT GREEN (-1825 2875);
DISPLAY INVISIBLE (-1825 2875);
FORCEPROP 1 LAST OFFPAGE TRUE
J 0
(-1600 2825);
DISPLAY 0.872340 (-1600 2825);
DISPLAY INVISIBLE (-1600 2825);
FORCEPROP 2 LAST CDS_LIB standard
J 0
(-1925 2950);
PAINT MONO (-1925 2950);
DISPLAY INVISIBLE (-1925 2950);
FORCEADD OFFPAGE..2
(4500 650);
FORCEPROP 2 LAST $XR0 215 
J 0
(4689 650);
DISPLAY 0.638298 (4689 650);
PAINT MONO (4689 650);
FORCEPROP 1 LAST COMMENT_BODY TRUE
J 0
(4455 555);
DISPLAY 0.872340 (4455 555);
PAINT GREEN (4455 555);
DISPLAY INVISIBLE (4455 555);
FORCEPROP 1 LAST OFFPAGE TRUE
J 0
(4825 525);
DISPLAY 0.872340 (4825 525);
DISPLAY INVISIBLE (4825 525);
FORCEPROP 2 LAST CDS_LIB standard
J 0
(4500 650);
DISPLAY INVISIBLE (4500 650);
FORCEPROP 2 LAST PATH I210
J 0
(4700 700);
DISPLAY 1.021277 (4700 700);
DISPLAY INVISIBLE (4700 700);
FORCEADD OFFPAGE..1
(1600 650);
FORCEPROP 2 LAST $XR1 204 
J 0
(1228 650);
DISPLAY 0.638298 (1228 650);
PAINT MONO (1228 650);
FORCEPROP 2 LAST $XR0 183 
J 0
(1348 650);
DISPLAY 0.638298 (1348 650);
PAINT MONO (1348 650);
FORCEPROP 1 LAST OFFPAGE TRUE
J 0
(1925 525);
DISPLAY 0.872340 (1925 525);
DISPLAY INVISIBLE (1925 525);
FORCEPROP 1 LAST COMMENT_BODY TRUE
J 0
(1725 550);
DISPLAY 0.872340 (1725 550);
PAINT GREEN (1725 550);
DISPLAY INVISIBLE (1725 550);
FORCEPROP 2 LAST PATH I212
J 0
(1325 700);
DISPLAY 1.021277 (1325 700);
DISPLAY INVISIBLE (1325 700);
FORCEPROP 2 LAST CDS_LIB standard
J 0
(1600 650);
DISPLAY INVISIBLE (1600 650);
FORCEADD Q_RES..1
(2950 650);
FORCEPROP 1 LAST PART_NUMBER CS03322FB03
J 0
(2850 700);
DISPLAY 0.510638 (2850 700);
DISPLAY INVISIBLE (2850 700);
FORCEPROP 1 LAST TOLERANCE 1%
J 0
(3175 650);
DISPLAY 0.510638 (3175 650);
FORCEPROP 1 LAST VALUE 33.2
J 2
(3150 650);
DISPLAY 0.510638 (3150 650);
FORCEPROP 1 LAST MATERIAL CHIP
J 0
(3250 650);
DISPLAY 0.510638 (3250 650);
FORCEPROP 1 LAST $LOCATION R474
J 0
(2700 650);
DISPLAY 0.638298 (2700 650);
FORCEPROP 1 LASTPIN (2850 650) $PN 1
J 0
(2862 662);
DISPLAY 0.787234 (2862 662);
PAINT MONO (2862 662);
FORCEPROP 1 LASTPIN (3050 650) $PN 2
J 0
(3012 662);
DISPLAY 0.787234 (3012 662);
PAINT MONO (3012 662);
FORCEPROP 1 LAST PACK_TYPE 0402LF
J 0
(2850 750);
DISPLAY 0.510638 (2850 750);
DISPLAY INVISIBLE (2850 750);
FORCEPROP 1 LAST WATTAGE 1/16W
J 2
(3150 750);
DISPLAY 0.510638 (3150 750);
DISPLAY INVISIBLE (3150 750);
FORCEPROP 1 LAST PATH I213
J 0
(2900 800);
DISPLAY 0.978723 (2900 800);
PAINT WHITE (2900 800);
DISPLAY INVISIBLE (2900 800);
FORCEPROP 2 LAST CDS_LIB pure_quanta
J 0
(2950 650);
DISPLAY INVISIBLE (2950 650);
FORCEPROP 0 LAST CDS_LOCATION R474
J 0
(2700 700);
DISPLAY 1.021277 (2700 700);
DISPLAY INVISIBLE (2700 700);
FORCEPROP 0 LAST $SEC 1
J 0
(2700 700);
DISPLAY 0.680851 (2700 700);
PAINT MONO (2700 700);
DISPLAY INVISIBLE (2700 700);
FORCEPROP 0 LAST CDS_SEC 1
J 0
(2700 700);
DISPLAY 1.021277 (2700 700);
DISPLAY INVISIBLE (2700 700);
FORCEADD OFFPAGE..5
(-1925 2900);
FORCEPROP 2 LAST $XR0 131 
J 0
(-2180 2900);
DISPLAY 0.638298 (-2180 2900);
PAINT MONO (-2180 2900);
FORCEPROP 2 LAST PATH I22
J 0
(-1875 2975);
DISPLAY 1.021277 (-1875 2975);
DISPLAY INVISIBLE (-1875 2975);
FORCEPROP 1 LAST COMMENT_BODY TRUE
J 0
(-1825 2825);
DISPLAY 1.170213 (-1825 2825);
PAINT GREEN (-1825 2825);
DISPLAY INVISIBLE (-1825 2825);
FORCEPROP 1 LAST OFFPAGE TRUE
J 0
(-1600 2775);
DISPLAY 0.872340 (-1600 2775);
DISPLAY INVISIBLE (-1600 2775);
FORCEPROP 2 LAST CDS_LIB standard
J 0
(-1925 2900);
PAINT MONO (-1925 2900);
DISPLAY INVISIBLE (-1925 2900);
FORCEADD Q_RES..1
(-1850 225);
FORCEPROP 1 LAST PART_NUMBER CS03322FB03
J 0
(-1950 300);
DISPLAY 0.404255 (-1950 300);
DISPLAY INVISIBLE (-1950 300);
FORCEPROP 1 LAST WATTAGE 1/16W
J 2
(-1700 325);
DISPLAY 0.404255 (-1700 325);
FORCEPROP 1 LAST VALUE 33.2
J 2
(-1675 225);
DISPLAY 0.510638 (-1675 225);
FORCEPROP 1 LAST MATERIAL CHIP
J 0
(-1575 225);
DISPLAY 0.510638 (-1575 225);
FORCEPROP 1 LAST TOLERANCE 1%
J 0
(-1650 225);
DISPLAY 0.510638 (-1650 225);
FORCEPROP 1 LAST PACK_TYPE 0402LF
J 0
(-1950 325);
DISPLAY 0.404255 (-1950 325);
FORCEPROP 1 LAST $LOCATION R1268
J 0
(-2100 225);
DISPLAY 0.638298 (-2100 225);
FORCEPROP 1 LASTPIN (-1950 225) $PN 1
J 0
(-1938 237);
DISPLAY 0.787234 (-1938 237);
FORCEPROP 1 LASTPIN (-1750 225) $PN 2
J 0
(-1788 237);
DISPLAY 0.787234 (-1788 237);
FORCEPROP 1 LAST PATH I222
J 0
(-1900 375);
DISPLAY 0.978723 (-1900 375);
PAINT WHITE (-1900 375);
DISPLAY INVISIBLE (-1900 375);
FORCEPROP 2 LAST CDS_LIB pure_quanta
J 0
(-1850 225);
PAINT MONO (-1850 225);
DISPLAY INVISIBLE (-1850 225);
FORCEPROP 2 LAST CDS_LOCATION R1268
J 0
(-1900 425);
DISPLAY 1.021277 (-1900 425);
DISPLAY INVISIBLE (-1900 425);
FORCEPROP 2 LAST $SEC 1
J 0
(-1900 425);
DISPLAY 0.680851 (-1900 425);
PAINT MONO (-1900 425);
DISPLAY INVISIBLE (-1900 425);
FORCEPROP 2 LAST CDS_SEC 1
J 0
(-1900 425);
DISPLAY 1.021277 (-1900 425);
DISPLAY INVISIBLE (-1900 425);
FORCEADD OFFPAGE..2
(-675 225);
FORCEPROP 2 LAST $XR0 183 
J 0
(-486 225);
DISPLAY 0.638298 (-486 225);
PAINT MONO (-486 225);
FORCEPROP 2 LAST CDS_LIB standard
J 0
(-675 225);
DISPLAY INVISIBLE (-675 225);
FORCEPROP 2 LAST PATH I223
J 0
(-475 275);
DISPLAY 1.021277 (-475 275);
DISPLAY INVISIBLE (-475 275);
FORCEPROP 1 LAST COMMENT_BODY TRUE
J 0
(-720 130);
DISPLAY 0.872340 (-720 130);
PAINT GREEN (-720 130);
DISPLAY INVISIBLE (-720 130);
FORCEPROP 1 LAST OFFPAGE TRUE
J 0
(-350 100);
DISPLAY 0.872340 (-350 100);
DISPLAY INVISIBLE (-350 100);
FORCEADD UNIVERSAL_GND..1
(-650 -25);
FORCEPROP 3 LASTPIN (-650 25) SIG_NAME GND\g
J 0
(-640 35);
DISPLAY 0.659574 (-640 35);
PAINT MONO (-640 35);
DISPLAY INVISIBLE (-640 35);
FORCEPROP 2 LAST CDS_LIB logical_power
J 0
(-650 -25);
PAINT MONO (-650 -25);
DISPLAY INVISIBLE (-650 -25);
FORCEPROP 1 LAST PATH I224
J 0
(-575 -25);
DISPLAY 0.872340 (-575 -25);
PAINT AQUA (-575 -25);
DISPLAY INVISIBLE (-575 -25);
FORCEPROP 1 LAST HDL_POWER GND
J 1
(-625 -100);
DISPLAY 0.872340 (-625 -100);
PAINT GREEN (-625 -100);
DISPLAY INVISIBLE (-625 -100);
FORCEADD Q_RES..1
(-1100 75);
FORCEPROP 1 LAST PART_NUMBER CS24752FB03
J 0
(-1225 150);
DISPLAY 0.404255 (-1225 150);
DISPLAY INVISIBLE (-1225 150);
FORCEPROP 1 LAST VALUE 4.75K
J 2
(-925 75);
DISPLAY 0.319149 (-925 75);
FORCEPROP 1 LAST PACK_TYPE 0402LF
J 0
(-1225 175);
DISPLAY 0.404255 (-1225 175);
FORCEPROP 1 LAST WATTAGE 1/16W
J 2
(-1000 175);
DISPLAY 0.404255 (-1000 175);
FORCEPROP 1 LAST TOLERANCE 1%
J 0
(-900 75);
DISPLAY 0.319149 (-900 75);
FORCEPROP 1 LAST MATERIAL CHIP
J 0
(-850 75);
DISPLAY 0.319149 (-850 75);
FORCEPROP 1 LAST $LOCATION R1269
J 0
(-1350 75);
DISPLAY 0.510638 (-1350 75);
FORCEPROP 1 LASTPIN (-1200 75) $PN 1
J 0
(-1188 87);
DISPLAY 0.787234 (-1188 87);
FORCEPROP 1 LASTPIN (-1000 75) $PN 2
J 0
(-1038 87);
DISPLAY 0.787234 (-1038 87);
FORCEPROP 1 LAST PATH I225
J 0
(-1150 225);
DISPLAY 0.978723 (-1150 225);
PAINT WHITE (-1150 225);
DISPLAY INVISIBLE (-1150 225);
FORCEPROP 2 LAST CDS_LIB pure_quanta
J 0
(-1100 75);
PAINT MONO (-1100 75);
DISPLAY INVISIBLE (-1100 75);
FORCEPROP 2 LAST CDS_LOCATION R1269
J 0
(-1150 275);
DISPLAY 1.021277 (-1150 275);
DISPLAY INVISIBLE (-1150 275);
FORCEPROP 2 LAST $SEC 1
J 0
(-1150 275);
DISPLAY 0.680851 (-1150 275);
PAINT MONO (-1150 275);
DISPLAY INVISIBLE (-1150 275);
FORCEPROP 2 LAST CDS_SEC 1
J 0
(-1150 275);
DISPLAY 1.021277 (-1150 275);
DISPLAY INVISIBLE (-1150 275);
FORCEADD OFFPAGE..1
(-1925 2650);
FORCEPROP 2 LAST $XR0 183 
J 0
(-2207 2650);
DISPLAY 0.638298 (-2207 2650);
PAINT MONO (-2207 2650);
FORCEPROP 1 LAST OFFPAGE TRUE
J 0
(-1600 2525);
DISPLAY 0.872340 (-1600 2525);
DISPLAY INVISIBLE (-1600 2525);
FORCEPROP 1 LAST COMMENT_BODY TRUE
J 0
(-1800 2550);
DISPLAY 1.170213 (-1800 2550);
PAINT GREEN (-1800 2550);
DISPLAY INVISIBLE (-1800 2550);
FORCEPROP 2 LAST PATH I227
J 0
(-2200 2700);
DISPLAY 1.021277 (-2200 2700);
DISPLAY INVISIBLE (-2200 2700);
FORCEPROP 2 LAST CDS_LIB standard
J 0
(-1925 2650);
PAINT MONO (-1925 2650);
DISPLAY INVISIBLE (-1925 2650);
FORCEADD OFFPAGE..1
(-1925 2600);
FORCEPROP 2 LAST $XR0 183 
J 0
(-2207 2600);
DISPLAY 0.638298 (-2207 2600);
PAINT MONO (-2207 2600);
FORCEPROP 1 LAST COMMENT_BODY TRUE
J 0
(-1800 2500);
DISPLAY 1.170213 (-1800 2500);
PAINT GREEN (-1800 2500);
DISPLAY INVISIBLE (-1800 2500);
FORCEPROP 1 LAST OFFPAGE TRUE
J 0
(-1600 2475);
DISPLAY 0.872340 (-1600 2475);
DISPLAY INVISIBLE (-1600 2475);
FORCEPROP 2 LAST PATH I228
J 0
(-2200 2650);
DISPLAY 1.021277 (-2200 2650);
DISPLAY INVISIBLE (-2200 2650);
FORCEPROP 2 LAST CDS_LIB standard
J 0
(-1925 2600);
PAINT MONO (-1925 2600);
DISPLAY INVISIBLE (-1925 2600);
FORCEADD OFFPAGE..1
(-1925 2550);
FORCEPROP 2 LAST $XR0 183 
J 0
(-2207 2550);
DISPLAY 0.638298 (-2207 2550);
PAINT MONO (-2207 2550);
FORCEPROP 1 LAST COMMENT_BODY TRUE
J 0
(-1800 2450);
DISPLAY 1.170213 (-1800 2450);
PAINT GREEN (-1800 2450);
DISPLAY INVISIBLE (-1800 2450);
FORCEPROP 1 LAST OFFPAGE TRUE
J 0
(-1600 2425);
DISPLAY 0.872340 (-1600 2425);
DISPLAY INVISIBLE (-1600 2425);
FORCEPROP 2 LAST PATH I229
J 0
(-2200 2600);
DISPLAY 1.021277 (-2200 2600);
DISPLAY INVISIBLE (-2200 2600);
FORCEPROP 2 LAST CDS_LIB standard
J 0
(-1925 2550);
PAINT MONO (-1925 2550);
DISPLAY INVISIBLE (-1925 2550);
FORCEADD OFFPAGE..5
(-1925 2850);
FORCEPROP 2 LAST $XR0 131 
J 0
(-2180 2850);
DISPLAY 0.638298 (-2180 2850);
PAINT MONO (-2180 2850);
FORCEPROP 2 LAST PATH I23
J 0
(-1875 2925);
DISPLAY 1.021277 (-1875 2925);
DISPLAY INVISIBLE (-1875 2925);
FORCEPROP 1 LAST COMMENT_BODY TRUE
J 0
(-1825 2775);
DISPLAY 1.170213 (-1825 2775);
PAINT GREEN (-1825 2775);
DISPLAY INVISIBLE (-1825 2775);
FORCEPROP 1 LAST OFFPAGE TRUE
J 0
(-1600 2725);
DISPLAY 0.872340 (-1600 2725);
DISPLAY INVISIBLE (-1600 2725);
FORCEPROP 2 LAST CDS_LIB standard
J 0
(-1925 2850);
PAINT MONO (-1925 2850);
DISPLAY INVISIBLE (-1925 2850);
FORCEADD OFFPAGE..1
(-1925 2500);
FORCEPROP 2 LAST $XR0 183 
J 0
(-2207 2500);
DISPLAY 0.638298 (-2207 2500);
PAINT MONO (-2207 2500);
FORCEPROP 2 LAST CDS_LIB standard
J 0
(-1925 2500);
PAINT MONO (-1925 2500);
DISPLAY INVISIBLE (-1925 2500);
FORCEPROP 2 LAST PATH I230
J 0
(-2200 2550);
DISPLAY 1.021277 (-2200 2550);
DISPLAY INVISIBLE (-2200 2550);
FORCEPROP 1 LAST OFFPAGE TRUE
J 0
(-1600 2375);
DISPLAY 0.872340 (-1600 2375);
DISPLAY INVISIBLE (-1600 2375);
FORCEPROP 1 LAST COMMENT_BODY TRUE
J 0
(-1800 2400);
DISPLAY 1.170213 (-1800 2400);
PAINT GREEN (-1800 2400);
DISPLAY INVISIBLE (-1800 2400);
FORCEADD Q_RES..1
(3475 -275);
FORCEPROP 1 LAST PART_NUMBER CS31002FB08
J 0
(3325 -200);
DISPLAY 0.638298 (3325 -200);
DISPLAY INVISIBLE (3325 -200);
FORCEPROP 1 LAST MATERIAL CHIP
J 0
(3800 -275);
DISPLAY 0.638298 (3800 -275);
FORCEPROP 1 LAST TOLERANCE 1%
J 0
(3700 -275);
DISPLAY 0.638298 (3700 -275);
FORCEPROP 1 LAST VALUE 10K
J 2
(3675 -275);
DISPLAY 0.638298 (3675 -275);
FORCEPROP 1 LAST $LOCATION R635
J 0
(3200 -275);
DISPLAY 0.638298 (3200 -275);
FORCEPROP 1 LASTPIN (3375 -275) $PN 1
J 0
(3387 -263);
DISPLAY 0.787234 (3387 -263);
FORCEPROP 1 LASTPIN (3575 -275) $PN 2
J 0
(3537 -263);
DISPLAY 0.787234 (3537 -263);
FORCEPROP 1 LAST PATH I234
J 0
(3425 -125);
DISPLAY 0.978723 (3425 -125);
PAINT WHITE (3425 -125);
DISPLAY INVISIBLE (3425 -125);
FORCEPROP 2 LAST CDS_LIB pure_quanta
J 0
(3475 -275);
PAINT MONO (3475 -275);
DISPLAY INVISIBLE (3475 -275);
FORCEPROP 1 LAST WATTAGE 1/16W
J 2
(3725 -150);
DISPLAY 0.638298 (3725 -150);
DISPLAY INVISIBLE (3725 -150);
FORCEPROP 1 LAST PACK_TYPE 0402LF
J 0
(3325 -150);
DISPLAY 0.638298 (3325 -150);
DISPLAY INVISIBLE (3325 -150);
FORCEPROP 2 LAST CDS_LOCATION R635
J 0
(3425 -75);
DISPLAY 1.021277 (3425 -75);
DISPLAY INVISIBLE (3425 -75);
FORCEPROP 2 LAST $SEC 1
J 0
(3425 -75);
DISPLAY 0.680851 (3425 -75);
PAINT MONO (3425 -75);
DISPLAY INVISIBLE (3425 -75);
FORCEPROP 2 LAST CDS_SEC 1
J 0
(3425 -75);
DISPLAY 1.021277 (3425 -75);
DISPLAY INVISIBLE (3425 -75);
FORCEADD OFFPAGE..5
(1925 -275);
FORCEPROP 2 LAST $XR0 183 
J 0
(1670 -275);
DISPLAY 0.638298 (1670 -275);
PAINT MONO (1670 -275);
FORCEPROP 1 LAST OFFPAGE TRUE
J 0
(2250 -400);
DISPLAY 0.872340 (2250 -400);
DISPLAY INVISIBLE (2250 -400);
FORCEPROP 1 LAST COMMENT_BODY TRUE
J 0
(2025 -350);
DISPLAY 1.170213 (2025 -350);
PAINT GREEN (2025 -350);
DISPLAY INVISIBLE (2025 -350);
FORCEPROP 2 LAST CDS_LIB standard
J 0
(1925 -275);
PAINT MONO (1925 -275);
DISPLAY INVISIBLE (1925 -275);
FORCEPROP 2 LAST PATH I235
J 0
(1650 -225);
DISPLAY 1.021277 (1650 -225);
DISPLAY INVISIBLE (1650 -225);
FORCEADD Q_RES..1
(3475 -325);
FORCEPROP 1 LAST PART_NUMBER CS31002FB08
J 0
(3325 -250);
DISPLAY 0.638298 (3325 -250);
DISPLAY INVISIBLE (3325 -250);
FORCEPROP 1 LAST MATERIAL CHIP
J 0
(3800 -325);
DISPLAY 0.638298 (3800 -325);
FORCEPROP 1 LAST VALUE 10K
J 2
(3675 -325);
DISPLAY 0.638298 (3675 -325);
FORCEPROP 1 LAST TOLERANCE 1%
J 0
(3700 -325);
DISPLAY 0.638298 (3700 -325);
FORCEPROP 1 LAST $LOCATION R727
J 0
(3200 -325);
DISPLAY 0.638298 (3200 -325);
FORCEPROP 1 LASTPIN (3375 -325) $PN 1
J 0
(3387 -313);
DISPLAY 0.787234 (3387 -313);
FORCEPROP 1 LASTPIN (3575 -325) $PN 2
J 0
(3537 -313);
DISPLAY 0.787234 (3537 -313);
FORCEPROP 2 LAST CDS_LIB pure_quanta
J 0
(3475 -325);
PAINT MONO (3475 -325);
DISPLAY INVISIBLE (3475 -325);
FORCEPROP 1 LAST WATTAGE 1/16W
J 2
(3725 -200);
DISPLAY 0.638298 (3725 -200);
DISPLAY INVISIBLE (3725 -200);
FORCEPROP 1 LAST PACK_TYPE 0402LF
J 0
(3325 -200);
DISPLAY 0.638298 (3325 -200);
DISPLAY INVISIBLE (3325 -200);
FORCEPROP 1 LAST PATH I236
J 0
(3425 -175);
DISPLAY 0.978723 (3425 -175);
PAINT WHITE (3425 -175);
DISPLAY INVISIBLE (3425 -175);
FORCEPROP 2 LAST CDS_LOCATION R727
J 0
(3425 -125);
DISPLAY 1.021277 (3425 -125);
DISPLAY INVISIBLE (3425 -125);
FORCEPROP 2 LAST $SEC 1
J 0
(3425 -125);
DISPLAY 0.680851 (3425 -125);
PAINT MONO (3425 -125);
DISPLAY INVISIBLE (3425 -125);
FORCEPROP 2 LAST CDS_SEC 1
J 0
(3425 -125);
DISPLAY 1.021277 (3425 -125);
DISPLAY INVISIBLE (3425 -125);
FORCEADD OFFPAGE..5
(1925 -325);
FORCEPROP 2 LAST $XR0 183 
J 0
(1670 -325);
DISPLAY 0.638298 (1670 -325);
PAINT MONO (1670 -325);
FORCEPROP 2 LAST PATH I237
J 0
(1650 -275);
DISPLAY 1.021277 (1650 -275);
DISPLAY INVISIBLE (1650 -275);
FORCEPROP 1 LAST OFFPAGE TRUE
J 0
(2250 -450);
DISPLAY 0.872340 (2250 -450);
DISPLAY INVISIBLE (2250 -450);
FORCEPROP 1 LAST COMMENT_BODY TRUE
J 0
(2025 -400);
DISPLAY 1.170213 (2025 -400);
PAINT GREEN (2025 -400);
DISPLAY INVISIBLE (2025 -400);
FORCEPROP 2 LAST CDS_LIB standard
J 0
(1925 -325);
PAINT MONO (1925 -325);
DISPLAY INVISIBLE (1925 -325);
FORCEADD OFFPAGE..5
(1925 -375);
FORCEPROP 2 LAST $XR0 183 
J 0
(1670 -375);
DISPLAY 0.638298 (1670 -375);
PAINT MONO (1670 -375);
FORCEPROP 2 LAST PATH I238
J 0
(1650 -325);
DISPLAY 1.021277 (1650 -325);
DISPLAY INVISIBLE (1650 -325);
FORCEPROP 2 LAST CDS_LIB standard
J 0
(1925 -375);
PAINT MONO (1925 -375);
DISPLAY INVISIBLE (1925 -375);
FORCEPROP 1 LAST COMMENT_BODY TRUE
J 0
(2025 -450);
DISPLAY 1.170213 (2025 -450);
PAINT GREEN (2025 -450);
DISPLAY INVISIBLE (2025 -450);
FORCEPROP 1 LAST OFFPAGE TRUE
J 0
(2250 -500);
DISPLAY 0.872340 (2250 -500);
DISPLAY INVISIBLE (2250 -500);
FORCEADD Q_RES..1
(3475 -375);
FORCEPROP 1 LAST PART_NUMBER CS31002FB08
J 0
(3325 -300);
DISPLAY 0.638298 (3325 -300);
DISPLAY INVISIBLE (3325 -300);
FORCEPROP 1 LAST VALUE 10K
J 2
(3675 -375);
DISPLAY 0.638298 (3675 -375);
FORCEPROP 1 LAST TOLERANCE 1%
J 0
(3700 -375);
DISPLAY 0.638298 (3700 -375);
FORCEPROP 1 LAST MATERIAL CHIP
J 0
(3800 -375);
DISPLAY 0.638298 (3800 -375);
FORCEPROP 1 LAST $LOCATION R770
J 0
(3200 -375);
DISPLAY 0.638298 (3200 -375);
FORCEPROP 1 LASTPIN (3375 -375) $PN 1
J 0
(3387 -363);
DISPLAY 0.787234 (3387 -363);
FORCEPROP 1 LASTPIN (3575 -375) $PN 2
J 0
(3537 -363);
DISPLAY 0.787234 (3537 -363);
FORCEPROP 1 LAST PACK_TYPE 0402LF
J 0
(3325 -250);
DISPLAY 0.638298 (3325 -250);
DISPLAY INVISIBLE (3325 -250);
FORCEPROP 1 LAST WATTAGE 1/16W
J 2
(3725 -250);
DISPLAY 0.638298 (3725 -250);
DISPLAY INVISIBLE (3725 -250);
FORCEPROP 2 LAST CDS_LIB pure_quanta
J 0
(3475 -375);
PAINT MONO (3475 -375);
DISPLAY INVISIBLE (3475 -375);
FORCEPROP 1 LAST PATH I239
J 0
(3425 -225);
DISPLAY 0.978723 (3425 -225);
PAINT WHITE (3425 -225);
DISPLAY INVISIBLE (3425 -225);
FORCEPROP 2 LAST CDS_LOCATION R770
J 0
(3425 -175);
DISPLAY 1.021277 (3425 -175);
DISPLAY INVISIBLE (3425 -175);
FORCEPROP 2 LAST $SEC 1
J 0
(3425 -175);
DISPLAY 0.680851 (3425 -175);
PAINT MONO (3425 -175);
DISPLAY INVISIBLE (3425 -175);
FORCEPROP 2 LAST CDS_SEC 1
J 0
(3425 -175);
DISPLAY 1.021277 (3425 -175);
DISPLAY INVISIBLE (3425 -175);
FORCEADD OFFPAGE..5
(-1925 2800);
FORCEPROP 2 LAST $XR0 131 
J 0
(-2180 2800);
DISPLAY 0.638298 (-2180 2800);
PAINT MONO (-2180 2800);
FORCEPROP 2 LAST PATH I24
J 0
(-1875 2875);
DISPLAY 1.021277 (-1875 2875);
DISPLAY INVISIBLE (-1875 2875);
FORCEPROP 1 LAST COMMENT_BODY TRUE
J 0
(-1825 2725);
DISPLAY 1.170213 (-1825 2725);
PAINT GREEN (-1825 2725);
DISPLAY INVISIBLE (-1825 2725);
FORCEPROP 1 LAST OFFPAGE TRUE
J 0
(-1600 2675);
DISPLAY 0.872340 (-1600 2675);
DISPLAY INVISIBLE (-1600 2675);
FORCEPROP 2 LAST CDS_LIB standard
J 0
(-1925 2800);
PAINT MONO (-1925 2800);
DISPLAY INVISIBLE (-1925 2800);
FORCEADD OFFPAGE..5
(1925 -425);
FORCEPROP 2 LAST $XR0 183 
J 0
(1670 -425);
DISPLAY 0.638298 (1670 -425);
PAINT MONO (1670 -425);
FORCEPROP 2 LAST PATH I240
J 0
(1650 -375);
DISPLAY 1.021277 (1650 -375);
DISPLAY INVISIBLE (1650 -375);
FORCEPROP 2 LAST CDS_LIB standard
J 0
(1925 -425);
PAINT MONO (1925 -425);
DISPLAY INVISIBLE (1925 -425);
FORCEPROP 1 LAST COMMENT_BODY TRUE
J 0
(2025 -500);
DISPLAY 1.170213 (2025 -500);
PAINT GREEN (2025 -500);
DISPLAY INVISIBLE (2025 -500);
FORCEPROP 1 LAST OFFPAGE TRUE
J 0
(2250 -550);
DISPLAY 0.872340 (2250 -550);
DISPLAY INVISIBLE (2250 -550);
FORCEADD Q_RES..1
(3475 -425);
FORCEPROP 1 LAST PART_NUMBER CS31002FB08
J 0
(3325 -350);
DISPLAY 0.638298 (3325 -350);
DISPLAY INVISIBLE (3325 -350);
FORCEPROP 1 LAST TOLERANCE 1%
J 0
(3700 -425);
DISPLAY 0.638298 (3700 -425);
FORCEPROP 1 LAST VALUE 10K
J 2
(3675 -425);
DISPLAY 0.638298 (3675 -425);
FORCEPROP 1 LAST MATERIAL CHIP
J 0
(3800 -425);
DISPLAY 0.638298 (3800 -425);
FORCEPROP 1 LAST $LOCATION R913
J 0
(3200 -425);
DISPLAY 0.638298 (3200 -425);
FORCEPROP 1 LASTPIN (3375 -425) $PN 1
J 0
(3387 -413);
DISPLAY 0.787234 (3387 -413);
FORCEPROP 1 LASTPIN (3575 -425) $PN 2
J 0
(3537 -413);
DISPLAY 0.787234 (3537 -413);
FORCEPROP 1 LAST PACK_TYPE 0402LF
J 0
(3325 -300);
DISPLAY 0.638298 (3325 -300);
DISPLAY INVISIBLE (3325 -300);
FORCEPROP 1 LAST WATTAGE 1/16W
J 2
(3725 -300);
DISPLAY 0.638298 (3725 -300);
DISPLAY INVISIBLE (3725 -300);
FORCEPROP 2 LAST CDS_LIB pure_quanta
J 0
(3475 -425);
PAINT MONO (3475 -425);
DISPLAY INVISIBLE (3475 -425);
FORCEPROP 1 LAST PATH I241
J 0
(3425 -275);
DISPLAY 0.978723 (3425 -275);
PAINT WHITE (3425 -275);
DISPLAY INVISIBLE (3425 -275);
FORCEPROP 2 LAST CDS_LOCATION R913
J 0
(3425 -225);
DISPLAY 1.021277 (3425 -225);
DISPLAY INVISIBLE (3425 -225);
FORCEPROP 2 LAST $SEC 1
J 0
(3425 -225);
DISPLAY 0.680851 (3425 -225);
PAINT MONO (3425 -225);
DISPLAY INVISIBLE (3425 -225);
FORCEPROP 2 LAST CDS_SEC 1
J 0
(3425 -225);
DISPLAY 1.021277 (3425 -225);
DISPLAY INVISIBLE (3425 -225);
FORCEADD OFFPAGE..2
(4450 4150);
FORCEPROP 2 LAST $XR1 223 
J 0
(4759 4150);
DISPLAY 0.638298 (4759 4150);
PAINT MONO (4759 4150);
FORCEPROP 2 LAST $XR0 198 
J 0
(4639 4150);
DISPLAY 0.638298 (4639 4150);
PAINT MONO (4639 4150);
FORCEPROP 1 LAST OFFPAGE TRUE
J 0
(4775 4025);
DISPLAY 0.872340 (4775 4025);
PAINT GREEN (4775 4025);
DISPLAY INVISIBLE (4775 4025);
FORCEPROP 1 LAST COMMENT_BODY TRUE
J 0
(4405 4055);
DISPLAY 0.872340 (4405 4055);
PAINT GREEN (4405 4055);
DISPLAY INVISIBLE (4405 4055);
FORCEPROP 2 LAST PATH I246
J 0
(4675 4200);
DISPLAY 1.021277 (4675 4200);
DISPLAY INVISIBLE (4675 4200);
FORCEPROP 2 LAST CDS_LIB standard
J 0
(4450 4150);
DISPLAY INVISIBLE (4450 4150);
FORCEADD OFFPAGE..2
(4450 4100);
FORCEPROP 2 LAST $XR1 205 
J 0
(4759 4100);
DISPLAY 0.638298 (4759 4100);
PAINT MONO (4759 4100);
FORCEPROP 2 LAST $XR0 204 
J 0
(4639 4100);
DISPLAY 0.638298 (4639 4100);
PAINT MONO (4639 4100);
FORCEPROP 2 LAST CDS_LIB standard
J 0
(4450 4100);
PAINT MONO (4450 4100);
DISPLAY INVISIBLE (4450 4100);
FORCEPROP 1 LAST OFFPAGE TRUE
J 0
(4775 3975);
DISPLAY 0.872340 (4775 3975);
PAINT GREEN (4775 3975);
DISPLAY INVISIBLE (4775 3975);
FORCEPROP 1 LAST COMMENT_BODY TRUE
J 0
(4405 4005);
DISPLAY 0.872340 (4405 4005);
PAINT GREEN (4405 4005);
DISPLAY INVISIBLE (4405 4005);
FORCEPROP 2 LAST PATH I247
J 0
(4800 4150);
DISPLAY 1.021277 (4800 4150);
DISPLAY INVISIBLE (4800 4150);
FORCEADD OFFPAGE..1
R 2
(4500 1025);
FORCEPROP 2 LAST $XR0 213 
J 0
(4686 1025);
DISPLAY 0.638298 (4686 1025);
PAINT MONO (4686 1025);
FORCEPROP 1 LAST COMMENT_BODY TRUE
J 2
(4375 925);
DISPLAY 0.872340 (4375 925);
PAINT GREEN (4375 925);
DISPLAY INVISIBLE (4375 925);
FORCEPROP 1 LAST OFFPAGE TRUE
J 2
(4175 900);
DISPLAY 0.872340 (4175 900);
DISPLAY INVISIBLE (4175 900);
FORCEPROP 2 LAST PATH I248
J 0
(4700 1075);
DISPLAY 1.021277 (4700 1075);
DISPLAY INVISIBLE (4700 1075);
FORCEPROP 2 LAST CDS_LIB standard
J 0
(4500 1025);
DISPLAY INVISIBLE (4500 1025);
FORCEADD OFFPAGE..1
R 2
(4450 3100);
FORCEPROP 2 LAST $XR0 183 
J 0
(4636 3100);
DISPLAY 0.638298 (4636 3100);
PAINT MONO (4636 3100);
FORCEPROP 2 LAST CDS_LIB standard
J 0
(4450 3100);
DISPLAY INVISIBLE (4450 3100);
FORCEPROP 2 LAST PATH I249
J 0
(4650 3150);
DISPLAY 1.021277 (4650 3150);
DISPLAY INVISIBLE (4650 3150);
FORCEPROP 1 LAST COMMENT_BODY TRUE
J 2
(4325 3000);
DISPLAY 0.872340 (4325 3000);
PAINT GREEN (4325 3000);
DISPLAY INVISIBLE (4325 3000);
FORCEPROP 1 LAST OFFPAGE TRUE
J 2
(4125 2975);
DISPLAY 0.872340 (4125 2975);
DISPLAY INVISIBLE (4125 2975);
FORCEADD OFFPAGE..5
(-1925 2750);
FORCEPROP 2 LAST $XR2 202 
J 0
(-2420 2750);
DISPLAY 0.638298 (-2420 2750);
PAINT MONO (-2420 2750);
FORCEPROP 2 LAST $XR1 131 
J 0
(-2300 2750);
DISPLAY 0.638298 (-2300 2750);
PAINT MONO (-2300 2750);
FORCEPROP 2 LAST $XR0 201 
J 0
(-2180 2750);
DISPLAY 0.638298 (-2180 2750);
PAINT MONO (-2180 2750);
FORCEPROP 2 LAST PATH I25
J 0
(-1875 2825);
DISPLAY 1.021277 (-1875 2825);
DISPLAY INVISIBLE (-1875 2825);
FORCEPROP 1 LAST COMMENT_BODY TRUE
J 0
(-1825 2675);
DISPLAY 1.170213 (-1825 2675);
PAINT GREEN (-1825 2675);
DISPLAY INVISIBLE (-1825 2675);
FORCEPROP 1 LAST OFFPAGE TRUE
J 0
(-1600 2625);
DISPLAY 0.872340 (-1600 2625);
DISPLAY INVISIBLE (-1600 2625);
FORCEPROP 2 LAST CDS_LIB standard
J 0
(-1925 2750);
PAINT MONO (-1925 2750);
DISPLAY INVISIBLE (-1925 2750);
FORCEADD OFFPAGE..1
(1575 1650);
FORCEPROP 2 LAST $XR0 215 
J 0
(1293 1650);
DISPLAY 0.638298 (1293 1650);
PAINT MONO (1293 1650);
FORCEPROP 2 LAST CDS_LIB standard
J 0
(1575 1650);
PAINT MONO (1575 1650);
DISPLAY INVISIBLE (1575 1650);
FORCEPROP 1 LAST OFFPAGE TRUE
J 0
(1900 1525);
DISPLAY 0.872340 (1900 1525);
DISPLAY INVISIBLE (1900 1525);
FORCEPROP 1 LAST COMMENT_BODY TRUE
J 0
(1700 1550);
DISPLAY 0.872340 (1700 1550);
PAINT GREEN (1700 1550);
DISPLAY INVISIBLE (1700 1550);
FORCEPROP 2 LAST PATH I250
J 0
(1300 1700);
DISPLAY 1.021277 (1300 1700);
DISPLAY INVISIBLE (1300 1700);
FORCEADD OFFPAGE..2
(4500 1650);
FORCEPROP 2 LAST $XR0 183 
J 0
(4689 1650);
DISPLAY 0.638298 (4689 1650);
PAINT MONO (4689 1650);
FORCEPROP 2 LAST PATH I252
J 0
(4850 1700);
DISPLAY 1.021277 (4850 1700);
DISPLAY INVISIBLE (4850 1700);
FORCEPROP 1 LAST COMMENT_BODY TRUE
J 0
(4455 1555);
DISPLAY 0.872340 (4455 1555);
PAINT GREEN (4455 1555);
DISPLAY INVISIBLE (4455 1555);
FORCEPROP 1 LAST OFFPAGE TRUE
J 0
(4825 1525);
DISPLAY 0.872340 (4825 1525);
DISPLAY INVISIBLE (4825 1525);
FORCEPROP 2 LAST CDS_LIB standard
J 0
(4500 1650);
PAINT MONO (4500 1650);
DISPLAY INVISIBLE (4500 1650);
FORCEADD Q_RES..1
(2950 1650);
FORCEPROP 1 LAST PART_NUMBER CS00002JB13
J 0
(2850 1700);
DISPLAY 0.404255 (2850 1700);
DISPLAY INVISIBLE (2850 1700);
FORCEPROP 1 LAST TOLERANCE 5%
J 0
(3125 1650);
DISPLAY 0.510638 (3125 1650);
FORCEPROP 1 LAST PACK_TYPE 0402LF
J 0
(2850 1725);
DISPLAY 0.404255 (2850 1725);
FORCEPROP 1 LAST WATTAGE 1/16W
J 2
(3100 1725);
DISPLAY 0.404255 (3100 1725);
FORCEPROP 1 LAST VALUE 0
J 2
(3100 1650);
DISPLAY 0.510638 (3100 1650);
FORCEPROP 1 LAST MATERIAL CHIP
J 0
(3200 1650);
DISPLAY 0.510638 (3200 1650);
FORCEPROP 1 LAST $LOCATION R2971
J 0
(2725 1650);
DISPLAY 0.638298 (2725 1650);
FORCEPROP 1 LASTPIN (2850 1650) $PN 1
J 0
(2862 1662);
DISPLAY 0.787234 (2862 1662);
PAINT MONO (2862 1662);
FORCEPROP 1 LASTPIN (3050 1650) $PN 2
J 0
(3012 1662);
DISPLAY 0.787234 (3012 1662);
PAINT MONO (3012 1662);
FORCEPROP 1 LAST PATH I253
J 0
(2900 1800);
DISPLAY 0.978723 (2900 1800);
PAINT WHITE (2900 1800);
DISPLAY INVISIBLE (2900 1800);
FORCEPROP 2 LAST CDS_LIB pure_quanta
J 0
(2950 1650);
DISPLAY INVISIBLE (2950 1650);
FORCEPROP 0 LAST CDS_LOCATION R2971
J 0
(3100 1750);
DISPLAY 1.021277 (3100 1750);
DISPLAY INVISIBLE (3100 1750);
FORCEPROP 0 LAST $SEC 1
J 0
(3100 1750);
DISPLAY 0.680851 (3100 1750);
PAINT MONO (3100 1750);
DISPLAY INVISIBLE (3100 1750);
FORCEPROP 0 LAST CDS_SEC 1
J 0
(3100 1750);
DISPLAY 1.021277 (3100 1750);
DISPLAY INVISIBLE (3100 1750);
FORCEADD CONN3_210HP1030BR1..1
R 2
(-3125 1525);
FORCEPROP 1 LAST PART_NUMBER DFHD03MS213
J 2
(-3062 1704);
DISPLAY 0.723404 (-3062 1704);
PAINT GREEN (-3062 1704);
DISPLAY INVISIBLE (-3062 1704);
FORCEPROP 2 LAST VALUE CONN3_210-HP1-030BR1
J 2
(-3050 1825);
DISPLAY 0.510638 (-3050 1825);
FORCEPROP 1 LAST MATERIAL EMPTY
J 2
(-3062 1649);
DISPLAY 0.723404 (-3062 1649);
PAINT RED (-3062 1649);
FORCEPROP 2 LAST PART_TYPE THLF
J 2
(-3050 1875);
DISPLAY 0.510638 (-3050 1875);
FORCEPROP 1 LAST $LOCATION JP4
J 2
(-3062 1754);
DISPLAY 0.723404 (-3062 1754);
PAINT GREEN (-3062 1754);
FORCEPROP 0 LASTPIN (-2925 1575) $PN 1
J 0
(-2915 1585);
DISPLAY 0.680851 (-2915 1585);
PAINT MONO (-2915 1585);
FORCEPROP 0 LASTPIN (-2925 1525) $PN 2
J 0
(-2915 1535);
DISPLAY 0.680851 (-2915 1535);
PAINT MONO (-2915 1535);
FORCEPROP 0 LASTPIN (-2925 1475) $PN 3
J 0
(-2915 1485);
DISPLAY 0.680851 (-2915 1485);
PAINT MONO (-2915 1485);
FORCEPROP 1 LAST CDS_LMAN_SYM_OUTLINE -50,100,50,-100
J 2
(-3125 1525);
DISPLAY 0.468085 (-3125 1525);
PAINT GREEN (-3125 1525);
DISPLAY INVISIBLE (-3125 1525);
FORCEPROP 1 LAST NEEDS_NO_SIZE TRUE
J 2
(-3125 1525);
DISPLAY 0.723404 (-3125 1525);
PAINT GREEN (-3125 1525);
DISPLAY INVISIBLE (-3125 1525);
FORCEPROP 1 LAST PATH I256
J 2
(-3125 1525);
DISPLAY 0.723404 (-3125 1525);
PAINT GREEN (-3125 1525);
DISPLAY INVISIBLE (-3125 1525);
FORCEPROP 2 LAST CDS_LIB pure_quanta
J 2
(-3125 1525);
DISPLAY INVISIBLE (-3125 1525);
FORCEPROP 0 LAST CDS_LOCATION JP4
J 0
(-3050 1900);
DISPLAY 1.021277 (-3050 1900);
DISPLAY INVISIBLE (-3050 1900);
FORCEPROP 0 LAST $SEC 1
J 0
(-3050 1900);
DISPLAY 0.680851 (-3050 1900);
PAINT MONO (-3050 1900);
DISPLAY INVISIBLE (-3050 1900);
FORCEPROP 0 LAST CDS_SEC 1
J 0
(-3050 1900);
DISPLAY 1.021277 (-3050 1900);
DISPLAY INVISIBLE (-3050 1900);
FORCEADD UNIVERSAL_GND..1
(-2825 1350);
FORCEPROP 3 LASTPIN (-2825 1400) SIG_NAME GND\g
J 0
(-2815 1410);
DISPLAY 0.659574 (-2815 1410);
PAINT MONO (-2815 1410);
DISPLAY INVISIBLE (-2815 1410);
FORCEPROP 1 LAST HDL_POWER GND
J 1
(-2800 1275);
DISPLAY 0.872340 (-2800 1275);
PAINT GREEN (-2800 1275);
DISPLAY INVISIBLE (-2800 1275);
FORCEPROP 1 LAST PATH I257
J 0
(-2750 1350);
DISPLAY 0.872340 (-2750 1350);
PAINT AQUA (-2750 1350);
DISPLAY INVISIBLE (-2750 1350);
FORCEPROP 2 LAST CDS_LIB logical_power
J 0
(-2825 1350);
DISPLAY INVISIBLE (-2825 1350);
FORCEADD OFFPAGE..1
R 2
(-1675 1575);
FORCEPROP 2 LAST $XR1 241 
J 0
(-1369 1575);
DISPLAY 0.638298 (-1369 1575);
PAINT MONO (-1369 1575);
FORCEPROP 2 LAST $XR0 183 
J 0
(-1489 1575);
DISPLAY 0.638298 (-1489 1575);
PAINT MONO (-1489 1575);
FORCEPROP 2 LAST CDS_LIB standard
J 0
(-1675 1575);
DISPLAY INVISIBLE (-1675 1575);
FORCEPROP 2 LAST PATH I258
J 0
(-1450 1625);
DISPLAY 1.021277 (-1450 1625);
DISPLAY INVISIBLE (-1450 1625);
FORCEPROP 1 LAST COMMENT_BODY TRUE
J 2
(-1800 1475);
DISPLAY 0.872340 (-1800 1475);
PAINT GREEN (-1800 1475);
DISPLAY INVISIBLE (-1800 1475);
FORCEPROP 1 LAST OFFPAGE TRUE
J 2
(-2000 1450);
DISPLAY 0.872340 (-2000 1450);
DISPLAY INVISIBLE (-2000 1450);
FORCEADD OFFPAGE..3
(-1675 1475);
FORCEPROP 2 LAST $XR1 241 
J 0
(-1341 1475);
DISPLAY 0.638298 (-1341 1475);
PAINT MONO (-1341 1475);
FORCEPROP 2 LAST $XR0 183 
J 0
(-1461 1475);
DISPLAY 0.638298 (-1461 1475);
PAINT MONO (-1461 1475);
FORCEPROP 1 LAST OFFPAGE TRUE
J 0
(-1350 1350);
DISPLAY 0.872340 (-1350 1350);
PAINT GREEN (-1350 1350);
DISPLAY INVISIBLE (-1350 1350);
FORCEPROP 1 LAST COMMENT_BODY TRUE
J 0
(-1725 1375);
DISPLAY 0.872340 (-1725 1375);
PAINT GREEN (-1725 1375);
DISPLAY INVISIBLE (-1725 1375);
FORCEPROP 2 LAST PATH I259
J 0
(-1450 1525);
DISPLAY 1.021277 (-1450 1525);
DISPLAY INVISIBLE (-1450 1525);
FORCEPROP 2 LAST CDS_LIB standard
J 0
(-1675 1475);
DISPLAY INVISIBLE (-1675 1475);
FORCEADD OFFPAGE..5
(-1925 2700);
FORCEPROP 2 LAST $XR0 131 
J 0
(-2180 2700);
DISPLAY 0.638298 (-2180 2700);
PAINT MONO (-2180 2700);
FORCEPROP 2 LAST PATH I26
J 0
(-1875 2775);
DISPLAY 1.021277 (-1875 2775);
DISPLAY INVISIBLE (-1875 2775);
FORCEPROP 1 LAST COMMENT_BODY TRUE
J 0
(-1825 2625);
DISPLAY 1.170213 (-1825 2625);
PAINT GREEN (-1825 2625);
DISPLAY INVISIBLE (-1825 2625);
FORCEPROP 1 LAST OFFPAGE TRUE
J 0
(-1600 2575);
DISPLAY 0.872340 (-1600 2575);
DISPLAY INVISIBLE (-1600 2575);
FORCEPROP 2 LAST CDS_LIB standard
J 0
(-1925 2700);
PAINT MONO (-1925 2700);
DISPLAY INVISIBLE (-1925 2700);
FORCEADD UNIVERSAL_GND..1
(-2825 775);
FORCEPROP 3 LASTPIN (-2825 825) SIG_NAME GND\g
J 0
(-2815 835);
DISPLAY 0.659574 (-2815 835);
PAINT MONO (-2815 835);
DISPLAY INVISIBLE (-2815 835);
FORCEPROP 1 LAST HDL_POWER GND
J 1
(-2800 700);
DISPLAY 0.872340 (-2800 700);
PAINT GREEN (-2800 700);
DISPLAY INVISIBLE (-2800 700);
FORCEPROP 2 LAST CDS_LIB logical_power
J 0
(-2825 775);
DISPLAY INVISIBLE (-2825 775);
FORCEPROP 1 LAST PATH I260
J 0
(-2750 775);
DISPLAY 0.872340 (-2750 775);
PAINT AQUA (-2750 775);
DISPLAY INVISIBLE (-2750 775);
FORCEADD OFFPAGE..3
(-1675 900);
FORCEPROP 2 LAST $XR0 183 
J 0
(-1461 900);
DISPLAY 0.638298 (-1461 900);
PAINT MONO (-1461 900);
FORCEPROP 1 LAST COMMENT_BODY TRUE
J 0
(-1725 800);
DISPLAY 0.872340 (-1725 800);
PAINT GREEN (-1725 800);
DISPLAY INVISIBLE (-1725 800);
FORCEPROP 1 LAST OFFPAGE TRUE
J 0
(-1350 775);
DISPLAY 0.872340 (-1350 775);
PAINT GREEN (-1350 775);
DISPLAY INVISIBLE (-1350 775);
FORCEPROP 2 LAST PATH I261
J 0
(-1450 950);
DISPLAY 1.021277 (-1450 950);
DISPLAY INVISIBLE (-1450 950);
FORCEPROP 2 LAST CDS_LIB standard
J 0
(-1675 900);
DISPLAY INVISIBLE (-1675 900);
FORCEADD OFFPAGE..1
R 2
(-1675 1000);
FORCEPROP 2 LAST $XR0 183 
J 0
(-1489 1000);
DISPLAY 0.638298 (-1489 1000);
PAINT MONO (-1489 1000);
FORCEPROP 2 LAST CDS_LIB standard
J 0
(-1675 1000);
DISPLAY INVISIBLE (-1675 1000);
FORCEPROP 1 LAST COMMENT_BODY TRUE
J 2
(-1800 900);
DISPLAY 0.872340 (-1800 900);
PAINT GREEN (-1800 900);
DISPLAY INVISIBLE (-1800 900);
FORCEPROP 1 LAST OFFPAGE TRUE
J 2
(-2000 875);
DISPLAY 0.872340 (-2000 875);
DISPLAY INVISIBLE (-2000 875);
FORCEPROP 2 LAST PATH I262
J 0
(-1450 1050);
DISPLAY 1.021277 (-1450 1050);
DISPLAY INVISIBLE (-1450 1050);
FORCEADD CONN3_210HP1030BR1..1
R 2
(-3125 950);
FORCEPROP 1 LAST PART_NUMBER DFHD03MS213
J 2
(-3062 1129);
DISPLAY 0.723404 (-3062 1129);
PAINT GREEN (-3062 1129);
DISPLAY INVISIBLE (-3062 1129);
FORCEPROP 2 LAST PART_TYPE THLF
J 2
(-3050 1300);
DISPLAY 0.510638 (-3050 1300);
FORCEPROP 1 LAST MATERIAL EMPTY
J 2
(-3062 1074);
DISPLAY 0.723404 (-3062 1074);
PAINT RED (-3062 1074);
FORCEPROP 2 LAST VALUE CONN3_210-HP1-030BR1
J 2
(-3050 1250);
DISPLAY 0.510638 (-3050 1250);
FORCEPROP 1 LAST $LOCATION JP9
J 2
(-3062 1179);
DISPLAY 0.723404 (-3062 1179);
PAINT GREEN (-3062 1179);
FORCEPROP 0 LASTPIN (-2925 1000) $PN 1
J 0
(-2915 1010);
DISPLAY 0.680851 (-2915 1010);
PAINT MONO (-2915 1010);
FORCEPROP 0 LASTPIN (-2925 950) $PN 2
J 0
(-2915 960);
DISPLAY 0.680851 (-2915 960);
PAINT MONO (-2915 960);
FORCEPROP 0 LASTPIN (-2925 900) $PN 3
J 0
(-2915 910);
DISPLAY 0.680851 (-2915 910);
PAINT MONO (-2915 910);
FORCEPROP 1 LAST CDS_LMAN_SYM_OUTLINE -50,100,50,-100
J 2
(-3125 950);
DISPLAY 0.468085 (-3125 950);
PAINT GREEN (-3125 950);
DISPLAY INVISIBLE (-3125 950);
FORCEPROP 1 LAST NEEDS_NO_SIZE TRUE
J 2
(-3125 950);
DISPLAY 0.723404 (-3125 950);
PAINT GREEN (-3125 950);
DISPLAY INVISIBLE (-3125 950);
FORCEPROP 2 LAST CDS_LIB pure_quanta
J 2
(-3125 950);
DISPLAY INVISIBLE (-3125 950);
FORCEPROP 1 LAST PATH I263
J 2
(-3125 950);
DISPLAY 0.723404 (-3125 950);
PAINT GREEN (-3125 950);
DISPLAY INVISIBLE (-3125 950);
FORCEPROP 0 LAST CDS_LOCATION JP9
J 0
(-3050 1325);
DISPLAY 1.021277 (-3050 1325);
DISPLAY INVISIBLE (-3050 1325);
FORCEPROP 0 LAST $SEC 1
J 0
(-3050 1325);
DISPLAY 0.680851 (-3050 1325);
PAINT MONO (-3050 1325);
DISPLAY INVISIBLE (-3050 1325);
FORCEPROP 0 LAST CDS_SEC 1
J 0
(-3050 1325);
DISPLAY 1.021277 (-3050 1325);
DISPLAY INVISIBLE (-3050 1325);
FORCEADD OFFPAGE..1
(-1925 4000);
FORCEPROP 2 LAST $XR0 215 
J 0
(-2207 4000);
DISPLAY 0.638298 (-2207 4000);
PAINT MONO (-2207 4000);
FORCEPROP 1 LAST COMMENT_BODY TRUE
J 0
(-1800 3900);
DISPLAY 1.170213 (-1800 3900);
PAINT GREEN (-1800 3900);
DISPLAY INVISIBLE (-1800 3900);
FORCEPROP 1 LAST OFFPAGE TRUE
J 0
(-1600 3875);
DISPLAY 0.872340 (-1600 3875);
DISPLAY INVISIBLE (-1600 3875);
FORCEPROP 2 LAST PATH I268
J 0
(-2200 4050);
DISPLAY 1.021277 (-2200 4050);
DISPLAY INVISIBLE (-2200 4050);
FORCEPROP 2 LAST CDS_LIB standard
J 0
(-1925 4000);
DISPLAY INVISIBLE (-1925 4000);
FORCEADD OFFPAGE..1
(-2975 225);
FORCEPROP 2 LAST $XR0 215 
J 0
(-3227 225);
DISPLAY 0.638298 (-3227 225);
PAINT MONO (-3227 225);
FORCEPROP 2 LAST CDS_LIB standard
J 0
(-2975 225);
DISPLAY INVISIBLE (-2975 225);
FORCEPROP 2 LAST PATH I269
J 0
(-3250 275);
DISPLAY 1.021277 (-3250 275);
DISPLAY INVISIBLE (-3250 275);
FORCEPROP 1 LAST OFFPAGE TRUE
J 0
(-2650 100);
DISPLAY 0.872340 (-2650 100);
DISPLAY INVISIBLE (-2650 100);
FORCEPROP 1 LAST COMMENT_BODY TRUE
J 0
(-2850 125);
DISPLAY 0.872340 (-2850 125);
PAINT GREEN (-2850 125);
DISPLAY INVISIBLE (-2850 125);
FORCEADD OFFPAGE..5
(-1925 2300);
FORCEPROP 2 LAST $XR0 131 
J 0
(-2180 2300);
DISPLAY 0.638298 (-2180 2300);
PAINT MONO (-2180 2300);
FORCEPROP 2 LAST PATH I27
J 0
(-1875 2375);
DISPLAY 1.021277 (-1875 2375);
DISPLAY INVISIBLE (-1875 2375);
FORCEPROP 1 LAST COMMENT_BODY TRUE
J 0
(-1825 2225);
DISPLAY 1.170213 (-1825 2225);
PAINT GREEN (-1825 2225);
DISPLAY INVISIBLE (-1825 2225);
FORCEPROP 1 LAST OFFPAGE TRUE
J 0
(-1600 2175);
DISPLAY 0.872340 (-1600 2175);
DISPLAY INVISIBLE (-1600 2175);
FORCEPROP 2 LAST CDS_LIB standard
J 0
(-1925 2300);
PAINT MONO (-1925 2300);
DISPLAY INVISIBLE (-1925 2300);
FORCEADD OFFPAGE..1
(-1925 2450);
FORCEPROP 2 LAST $XR0 183 
J 0
(-2207 2450);
DISPLAY 0.638298 (-2207 2450);
PAINT MONO (-2207 2450);
FORCEPROP 1 LAST COMMENT_BODY TRUE
J 0
(-1800 2350);
DISPLAY 1.170213 (-1800 2350);
PAINT GREEN (-1800 2350);
DISPLAY INVISIBLE (-1800 2350);
FORCEPROP 1 LAST OFFPAGE TRUE
J 0
(-1600 2325);
DISPLAY 0.872340 (-1600 2325);
DISPLAY INVISIBLE (-1600 2325);
FORCEPROP 2 LAST PATH I271
J 0
(-1875 2525);
DISPLAY 1.021277 (-1875 2525);
DISPLAY INVISIBLE (-1875 2525);
FORCEPROP 2 LAST CDS_LIB standard
J 0
(-1925 2450);
DISPLAY INVISIBLE (-1925 2450);
FORCEADD Q_RES..1
(3475 -225);
FORCEPROP 1 LAST PART_NUMBER CS31002FB08
J 0
(3325 -150);
DISPLAY 0.638298 (3325 -150);
DISPLAY INVISIBLE (3325 -150);
FORCEPROP 1 LAST MATERIAL CHIP
J 0
(3800 -225);
DISPLAY 0.638298 (3800 -225);
FORCEPROP 1 LAST TOLERANCE 1%
J 0
(3700 -225);
DISPLAY 0.638298 (3700 -225);
FORCEPROP 1 LAST VALUE 10K
J 2
(3675 -225);
DISPLAY 0.638298 (3675 -225);
FORCEPROP 1 LAST $LOCATION R3938
J 0
(3200 -225);
DISPLAY 0.638298 (3200 -225);
FORCEPROP 1 LASTPIN (3375 -225) $PN 1
J 0
(3387 -213);
DISPLAY 0.787234 (3387 -213);
FORCEPROP 1 LASTPIN (3575 -225) $PN 2
J 0
(3537 -213);
DISPLAY 0.787234 (3537 -213);
FORCEPROP 1 LAST PACK_TYPE 0402LF
J 0
(3325 -100);
DISPLAY 0.638298 (3325 -100);
DISPLAY INVISIBLE (3325 -100);
FORCEPROP 1 LAST WATTAGE 1/16W
J 2
(3725 -100);
DISPLAY 0.638298 (3725 -100);
DISPLAY INVISIBLE (3725 -100);
FORCEPROP 2 LAST CDS_LIB pure_quanta
J 0
(3475 -225);
PAINT MONO (3475 -225);
DISPLAY INVISIBLE (3475 -225);
FORCEPROP 1 LAST PATH I272
J 0
(3425 -75);
DISPLAY 0.978723 (3425 -75);
PAINT WHITE (3425 -75);
DISPLAY INVISIBLE (3425 -75);
FORCEPROP 2 LAST CDS_LOCATION R3938
J 0
(3425 -25);
DISPLAY 1.021277 (3425 -25);
DISPLAY INVISIBLE (3425 -25);
FORCEPROP 2 LAST $SEC 1
J 0
(3425 -25);
DISPLAY 0.680851 (3425 -25);
PAINT MONO (3425 -25);
DISPLAY INVISIBLE (3425 -25);
FORCEPROP 2 LAST CDS_SEC 1
J 0
(3425 -25);
DISPLAY 1.021277 (3425 -25);
DISPLAY INVISIBLE (3425 -25);
FORCEADD OFFPAGE..5
(1925 -225);
FORCEPROP 2 LAST $XR0 183 
J 0
(1670 -225);
DISPLAY 0.638298 (1670 -225);
PAINT MONO (1670 -225);
FORCEPROP 2 LAST PATH I273
J 0
(1650 -175);
DISPLAY 1.021277 (1650 -175);
DISPLAY INVISIBLE (1650 -175);
FORCEPROP 2 LAST CDS_LIB standard
J 0
(1925 -225);
PAINT MONO (1925 -225);
DISPLAY INVISIBLE (1925 -225);
FORCEPROP 1 LAST COMMENT_BODY TRUE
J 0
(2025 -300);
DISPLAY 1.170213 (2025 -300);
PAINT GREEN (2025 -300);
DISPLAY INVISIBLE (2025 -300);
FORCEPROP 1 LAST OFFPAGE TRUE
J 0
(2250 -350);
DISPLAY 0.872340 (2250 -350);
DISPLAY INVISIBLE (2250 -350);
FORCEADD Q_RES..1
(-2700 4000);
FORCEPROP 1 LAST PART_NUMBER CS00002JB13
J 0
(-2975 3875);
DISPLAY 0.723404 (-2975 3875);
PAINT WHITE (-2975 3875);
DISPLAY INVISIBLE (-2975 3875);
FORCEPROP 1 LAST PACK_TYPE 0402LF
J 0
(-2750 3950);
DISPLAY 0.574468 (-2750 3950);
FORCEPROP 1 LAST MATERIAL EMPTY
J 0
(-2875 3950);
DISPLAY 0.574468 (-2875 3950);
PAINT RED (-2875 3950);
FORCEPROP 1 LAST VALUE 0
J 2
(-2550 4000);
DISPLAY 0.574468 (-2550 4000);
FORCEPROP 1 LAST $LOCATION R4083
J 0
(-2900 4000);
DISPLAY 0.638298 (-2900 4000);
FORCEPROP 1 LASTPIN (-2800 4000) $PN 1
J 0
(-2788 4012);
DISPLAY 0.787234 (-2788 4012);
PAINT MONO (-2788 4012);
FORCEPROP 1 LASTPIN (-2600 4000) $PN 2
J 0
(-2638 4012);
DISPLAY 0.787234 (-2638 4012);
PAINT MONO (-2638 4012);
FORCEPROP 1 LAST TOLERANCE 5%
J 0
(-2900 3925);
DISPLAY 0.723404 (-2900 3925);
PAINT SKYBLUE (-2900 3925);
DISPLAY INVISIBLE (-2900 3925);
FORCEPROP 1 LAST WATTAGE 1/16W
J 2
(-2625 3925);
DISPLAY 0.723404 (-2625 3925);
PAINT SKYBLUE (-2625 3925);
DISPLAY INVISIBLE (-2625 3925);
FORCEPROP 2 LAST CDS_LIB pure_quanta
J 0
(-2700 4000);
DISPLAY INVISIBLE (-2700 4000);
FORCEPROP 1 LAST PATH I274
J 0
(-2750 4150);
DISPLAY 0.978723 (-2750 4150);
PAINT WHITE (-2750 4150);
DISPLAY INVISIBLE (-2750 4150);
FORCEPROP 0 LAST CDS_LOCATION R4083
J 0
(-2550 4050);
DISPLAY 1.021277 (-2550 4050);
DISPLAY INVISIBLE (-2550 4050);
FORCEPROP 0 LAST $SEC 1
J 0
(-2550 4050);
DISPLAY 0.680851 (-2550 4050);
PAINT MONO (-2550 4050);
DISPLAY INVISIBLE (-2550 4050);
FORCEPROP 0 LAST CDS_SEC 1
J 0
(-2550 4050);
DISPLAY 1.021277 (-2550 4050);
DISPLAY INVISIBLE (-2550 4050);
FORCEADD Q_RES..1
(-2700 3900);
FORCEPROP 1 LAST PART_NUMBER CS00002JB13
J 0
(-2975 3775);
DISPLAY 0.723404 (-2975 3775);
PAINT WHITE (-2975 3775);
DISPLAY INVISIBLE (-2975 3775);
FORCEPROP 1 LAST VALUE 0
J 2
(-2550 3900);
DISPLAY 0.574468 (-2550 3900);
FORCEPROP 1 LAST PACK_TYPE 0402LF
J 0
(-2750 3850);
DISPLAY 0.574468 (-2750 3850);
FORCEPROP 1 LAST MATERIAL EMPTY
J 0
(-2875 3850);
DISPLAY 0.574468 (-2875 3850);
FORCEPROP 1 LAST $LOCATION R4084
J 0
(-2900 3900);
DISPLAY 0.638298 (-2900 3900);
FORCEPROP 1 LASTPIN (-2800 3900) $PN 1
J 0
(-2788 3912);
DISPLAY 0.787234 (-2788 3912);
PAINT MONO (-2788 3912);
FORCEPROP 1 LASTPIN (-2600 3900) $PN 2
J 0
(-2638 3912);
DISPLAY 0.787234 (-2638 3912);
PAINT MONO (-2638 3912);
FORCEPROP 1 LAST WATTAGE 1/16W
J 2
(-2625 3825);
DISPLAY 0.723404 (-2625 3825);
PAINT SKYBLUE (-2625 3825);
DISPLAY INVISIBLE (-2625 3825);
FORCEPROP 1 LAST TOLERANCE 5%
J 0
(-2900 3825);
DISPLAY 0.723404 (-2900 3825);
PAINT SKYBLUE (-2900 3825);
DISPLAY INVISIBLE (-2900 3825);
FORCEPROP 2 LAST CDS_LIB pure_quanta
J 0
(-2700 3900);
DISPLAY INVISIBLE (-2700 3900);
FORCEPROP 1 LAST PATH I275
J 0
(-2750 4050);
DISPLAY 0.978723 (-2750 4050);
PAINT WHITE (-2750 4050);
DISPLAY INVISIBLE (-2750 4050);
FORCEPROP 0 LAST CDS_LOCATION R4084
J 0
(-2550 3950);
DISPLAY 1.021277 (-2550 3950);
DISPLAY INVISIBLE (-2550 3950);
FORCEPROP 0 LAST $SEC 1
J 0
(-2550 3950);
DISPLAY 0.680851 (-2550 3950);
PAINT MONO (-2550 3950);
DISPLAY INVISIBLE (-2550 3950);
FORCEPROP 0 LAST CDS_SEC 1
J 0
(-2550 3950);
DISPLAY 1.021277 (-2550 3950);
DISPLAY INVISIBLE (-2550 3950);
FORCEADD OFFPAGE..1
(-3600 4000);
FORCEPROP 2 LAST $XR0 191 
J 0
(-3882 4000);
DISPLAY 0.638298 (-3882 4000);
PAINT MONO (-3882 4000);
FORCEPROP 2 LAST PATH I276
J 0
(-3850 4050);
DISPLAY 1.021277 (-3850 4050);
DISPLAY INVISIBLE (-3850 4050);
FORCEPROP 1 LAST COMMENT_BODY TRUE
J 0
(-3475 3900);
DISPLAY 1.170213 (-3475 3900);
PAINT GREEN (-3475 3900);
DISPLAY INVISIBLE (-3475 3900);
FORCEPROP 1 LAST OFFPAGE TRUE
J 0
(-3275 3875);
DISPLAY 0.872340 (-3275 3875);
DISPLAY INVISIBLE (-3275 3875);
FORCEPROP 2 LAST CDS_LIB standard
J 0
(-3600 4000);
DISPLAY INVISIBLE (-3600 4000);
FORCEADD OFFPAGE..1
(-3600 3900);
FORCEPROP 2 LAST $XR1 215 
J 0
(-3882 3864);
DISPLAY 0.638298 (-3882 3864);
PAINT MONO (-3882 3864);
FORCEPROP 2 LAST $XR0 191 
J 0
(-3882 3900);
DISPLAY 0.638298 (-3882 3900);
PAINT MONO (-3882 3900);
FORCEPROP 2 LAST CDS_LIB standard
J 0
(-3600 3900);
DISPLAY INVISIBLE (-3600 3900);
FORCEPROP 1 LAST OFFPAGE TRUE
J 0
(-3275 3775);
DISPLAY 0.872340 (-3275 3775);
PAINT GREEN (-3275 3775);
DISPLAY INVISIBLE (-3275 3775);
FORCEPROP 1 LAST COMMENT_BODY TRUE
J 0
(-3475 3800);
DISPLAY 0.872340 (-3475 3800);
PAINT GREEN (-3475 3800);
DISPLAY INVISIBLE (-3475 3800);
FORCEPROP 2 LAST PATH I277
J 0
(-3850 3950);
DISPLAY 1.021277 (-3850 3950);
DISPLAY INVISIBLE (-3850 3950);
FORCEADD OFFPAGE..1
(-1925 4300);
FORCEPROP 2 LAST $XR0 183 
J 0
(-2207 4300);
DISPLAY 0.638298 (-2207 4300);
PAINT MONO (-2207 4300);
FORCEPROP 1 LAST OFFPAGE TRUE
J 0
(-1600 4175);
DISPLAY 0.872340 (-1600 4175);
DISPLAY INVISIBLE (-1600 4175);
FORCEPROP 1 LAST COMMENT_BODY TRUE
J 0
(-1800 4200);
DISPLAY 1.170213 (-1800 4200);
PAINT GREEN (-1800 4200);
DISPLAY INVISIBLE (-1800 4200);
FORCEPROP 2 LAST PATH I278
J 0
(-1875 4375);
DISPLAY 1.021277 (-1875 4375);
DISPLAY INVISIBLE (-1875 4375);
FORCEPROP 2 LAST CDS_LIB standard
J 0
(-1925 4300);
DISPLAY INVISIBLE (-1925 4300);
FORCEADD OFFPAGE..1
(-1925 4250);
FORCEPROP 2 LAST $XR0 183 
J 0
(-2207 4250);
DISPLAY 0.638298 (-2207 4250);
PAINT MONO (-2207 4250);
FORCEPROP 1 LAST COMMENT_BODY TRUE
J 0
(-1800 4150);
DISPLAY 1.170213 (-1800 4150);
PAINT GREEN (-1800 4150);
DISPLAY INVISIBLE (-1800 4150);
FORCEPROP 1 LAST OFFPAGE TRUE
J 0
(-1600 4125);
DISPLAY 0.872340 (-1600 4125);
DISPLAY INVISIBLE (-1600 4125);
FORCEPROP 2 LAST PATH I279
J 0
(-1875 4325);
DISPLAY 1.021277 (-1875 4325);
DISPLAY INVISIBLE (-1875 4325);
FORCEPROP 2 LAST CDS_LIB standard
J 0
(-1925 4250);
DISPLAY INVISIBLE (-1925 4250);
FORCEADD OFFPAGE..5
(-1925 2250);
FORCEPROP 2 LAST $XR0 131 
J 0
(-2180 2250);
DISPLAY 0.638298 (-2180 2250);
PAINT MONO (-2180 2250);
FORCEPROP 2 LAST PATH I28
J 0
(-1875 2325);
DISPLAY 1.021277 (-1875 2325);
DISPLAY INVISIBLE (-1875 2325);
FORCEPROP 1 LAST COMMENT_BODY TRUE
J 0
(-1825 2175);
DISPLAY 1.170213 (-1825 2175);
PAINT GREEN (-1825 2175);
DISPLAY INVISIBLE (-1825 2175);
FORCEPROP 1 LAST OFFPAGE TRUE
J 0
(-1600 2125);
DISPLAY 0.872340 (-1600 2125);
DISPLAY INVISIBLE (-1600 2125);
FORCEPROP 2 LAST CDS_LIB standard
J 0
(-1925 2250);
PAINT MONO (-1925 2250);
DISPLAY INVISIBLE (-1925 2250);
FORCEADD OFFPAGE..1
(-1925 4100);
FORCEPROP 2 LAST $XR0 183 
J 0
(-2207 4100);
DISPLAY 0.638298 (-2207 4100);
PAINT MONO (-2207 4100);
FORCEPROP 1 LAST COMMENT_BODY TRUE
J 0
(-1800 4000);
DISPLAY 1.170213 (-1800 4000);
PAINT GREEN (-1800 4000);
DISPLAY INVISIBLE (-1800 4000);
FORCEPROP 1 LAST OFFPAGE TRUE
J 0
(-1600 3975);
DISPLAY 0.872340 (-1600 3975);
DISPLAY INVISIBLE (-1600 3975);
FORCEPROP 2 LAST PATH I280
J 0
(-1875 4175);
DISPLAY 1.021277 (-1875 4175);
DISPLAY INVISIBLE (-1875 4175);
FORCEPROP 2 LAST CDS_LIB standard
J 0
(-1925 4100);
DISPLAY INVISIBLE (-1925 4100);
FORCEADD OFFPAGE..1
(-1925 4050);
FORCEPROP 2 LAST $XR0 183 
J 0
(-2207 4050);
DISPLAY 0.638298 (-2207 4050);
PAINT MONO (-2207 4050);
FORCEPROP 1 LAST COMMENT_BODY TRUE
J 0
(-1800 3950);
DISPLAY 1.170213 (-1800 3950);
PAINT GREEN (-1800 3950);
DISPLAY INVISIBLE (-1800 3950);
FORCEPROP 1 LAST OFFPAGE TRUE
J 0
(-1600 3925);
DISPLAY 0.872340 (-1600 3925);
DISPLAY INVISIBLE (-1600 3925);
FORCEPROP 2 LAST PATH I281
J 0
(-1875 4125);
DISPLAY 1.021277 (-1875 4125);
DISPLAY INVISIBLE (-1875 4125);
FORCEPROP 2 LAST CDS_LIB standard
J 0
(-1925 4050);
DISPLAY INVISIBLE (-1925 4050);
FORCEADD OFFPAGE..1
(-1925 3850);
FORCEPROP 2 LAST $XR0 183 
J 0
(-2207 3850);
DISPLAY 0.638298 (-2207 3850);
PAINT MONO (-2207 3850);
FORCEPROP 1 LAST COMMENT_BODY TRUE
J 0
(-1800 3750);
DISPLAY 1.170213 (-1800 3750);
PAINT GREEN (-1800 3750);
DISPLAY INVISIBLE (-1800 3750);
FORCEPROP 1 LAST OFFPAGE TRUE
J 0
(-1600 3725);
DISPLAY 0.872340 (-1600 3725);
DISPLAY INVISIBLE (-1600 3725);
FORCEPROP 2 LAST PATH I282
J 0
(-1875 3925);
DISPLAY 1.021277 (-1875 3925);
DISPLAY INVISIBLE (-1875 3925);
FORCEPROP 2 LAST CDS_LIB standard
J 0
(-1925 3850);
DISPLAY INVISIBLE (-1925 3850);
FORCEADD Q_RES..1
(-1425 -600);
FORCEPROP 1 LAST PART_NUMBER CS31002FB08
J 0
(-1575 -525);
DISPLAY 0.638298 (-1575 -525);
DISPLAY INVISIBLE (-1575 -525);
FORCEPROP 1 LAST MATERIAL CHIP
J 0
(-1100 -600);
DISPLAY 0.638298 (-1100 -600);
FORCEPROP 1 LAST TOLERANCE 1%
J 0
(-1200 -600);
DISPLAY 0.638298 (-1200 -600);
FORCEPROP 1 LAST VALUE 10K
J 2
(-1225 -600);
DISPLAY 0.638298 (-1225 -600);
FORCEPROP 1 LAST $LOCATION R4095
J 0
(-1625 -600);
DISPLAY 0.638298 (-1625 -600);
FORCEPROP 1 LASTPIN (-1525 -600) $PN 1
J 0
(-1513 -588);
DISPLAY 0.787234 (-1513 -588);
PAINT MONO (-1513 -588);
FORCEPROP 1 LASTPIN (-1325 -600) $PN 2
J 0
(-1363 -588);
DISPLAY 0.787234 (-1363 -588);
PAINT MONO (-1363 -588);
FORCEPROP 2 LAST CDS_LIB pure_quanta
J 0
(-1425 -600);
DISPLAY INVISIBLE (-1425 -600);
FORCEPROP 1 LAST PATH I284
J 0
(-1475 -450);
DISPLAY 0.978723 (-1475 -450);
PAINT WHITE (-1475 -450);
DISPLAY INVISIBLE (-1475 -450);
FORCEPROP 1 LAST PACK_TYPE 0402LF
J 0
(-1575 -475);
DISPLAY 0.638298 (-1575 -475);
DISPLAY INVISIBLE (-1575 -475);
FORCEPROP 1 LAST WATTAGE 1/16W
J 2
(-1175 -475);
DISPLAY 0.638298 (-1175 -475);
DISPLAY INVISIBLE (-1175 -475);
FORCEPROP 0 LAST CDS_LOCATION R4095
J 0
(-1100 -550);
DISPLAY 1.021277 (-1100 -550);
DISPLAY INVISIBLE (-1100 -550);
FORCEPROP 0 LAST $SEC 1
J 0
(-1100 -550);
DISPLAY 0.680851 (-1100 -550);
PAINT MONO (-1100 -550);
DISPLAY INVISIBLE (-1100 -550);
FORCEPROP 0 LAST CDS_SEC 1
J 0
(-1100 -550);
DISPLAY 1.021277 (-1100 -550);
DISPLAY INVISIBLE (-1100 -550);
FORCEADD Q_RES..1
(-1425 -650);
FORCEPROP 1 LAST PART_NUMBER CS31002FB08
J 0
(-1575 -575);
DISPLAY 0.638298 (-1575 -575);
DISPLAY INVISIBLE (-1575 -575);
FORCEPROP 1 LAST MATERIAL CHIP
J 0
(-1100 -650);
DISPLAY 0.638298 (-1100 -650);
FORCEPROP 1 LAST TOLERANCE 1%
J 0
(-1200 -650);
DISPLAY 0.638298 (-1200 -650);
FORCEPROP 1 LAST VALUE 10K
J 2
(-1225 -650);
DISPLAY 0.638298 (-1225 -650);
FORCEPROP 1 LAST $LOCATION R4096
J 0
(-1625 -650);
DISPLAY 0.638298 (-1625 -650);
FORCEPROP 1 LASTPIN (-1525 -650) $PN 1
J 0
(-1513 -638);
DISPLAY 0.787234 (-1513 -638);
PAINT MONO (-1513 -638);
FORCEPROP 1 LASTPIN (-1325 -650) $PN 2
J 0
(-1363 -638);
DISPLAY 0.787234 (-1363 -638);
PAINT MONO (-1363 -638);
FORCEPROP 2 LAST CDS_LIB pure_quanta
J 0
(-1425 -650);
DISPLAY INVISIBLE (-1425 -650);
FORCEPROP 1 LAST PATH I285
J 0
(-1475 -500);
DISPLAY 0.978723 (-1475 -500);
PAINT WHITE (-1475 -500);
DISPLAY INVISIBLE (-1475 -500);
FORCEPROP 1 LAST PACK_TYPE 0402LF
J 0
(-1575 -525);
DISPLAY 0.638298 (-1575 -525);
DISPLAY INVISIBLE (-1575 -525);
FORCEPROP 1 LAST WATTAGE 1/16W
J 2
(-1175 -525);
DISPLAY 0.638298 (-1175 -525);
DISPLAY INVISIBLE (-1175 -525);
FORCEPROP 0 LAST CDS_LOCATION R4096
J 0
(-1100 -600);
DISPLAY 1.021277 (-1100 -600);
DISPLAY INVISIBLE (-1100 -600);
FORCEPROP 0 LAST $SEC 1
J 0
(-1100 -600);
DISPLAY 0.680851 (-1100 -600);
PAINT MONO (-1100 -600);
DISPLAY INVISIBLE (-1100 -600);
FORCEPROP 0 LAST CDS_SEC 1
J 0
(-1100 -600);
DISPLAY 1.021277 (-1100 -600);
DISPLAY INVISIBLE (-1100 -600);
FORCEADD Q_RES..1
(-1425 -700);
FORCEPROP 1 LAST PART_NUMBER CS31002FB08
J 0
(-1575 -625);
DISPLAY 0.638298 (-1575 -625);
DISPLAY INVISIBLE (-1575 -625);
FORCEPROP 1 LAST VALUE 10K
J 2
(-1225 -700);
DISPLAY 0.638298 (-1225 -700);
FORCEPROP 1 LAST MATERIAL CHIP
J 0
(-1100 -700);
DISPLAY 0.638298 (-1100 -700);
FORCEPROP 1 LAST TOLERANCE 1%
J 0
(-1200 -700);
DISPLAY 0.638298 (-1200 -700);
FORCEPROP 1 LAST $LOCATION R4097
J 0
(-1625 -700);
DISPLAY 0.638298 (-1625 -700);
FORCEPROP 1 LASTPIN (-1525 -700) $PN 1
J 0
(-1513 -688);
DISPLAY 0.787234 (-1513 -688);
PAINT MONO (-1513 -688);
FORCEPROP 1 LASTPIN (-1325 -700) $PN 2
J 0
(-1363 -688);
DISPLAY 0.787234 (-1363 -688);
PAINT MONO (-1363 -688);
FORCEPROP 2 LAST CDS_LIB pure_quanta
J 0
(-1425 -700);
DISPLAY INVISIBLE (-1425 -700);
FORCEPROP 1 LAST PATH I286
J 0
(-1475 -550);
DISPLAY 0.978723 (-1475 -550);
PAINT WHITE (-1475 -550);
DISPLAY INVISIBLE (-1475 -550);
FORCEPROP 1 LAST PACK_TYPE 0402LF
J 0
(-1575 -575);
DISPLAY 0.638298 (-1575 -575);
DISPLAY INVISIBLE (-1575 -575);
FORCEPROP 1 LAST WATTAGE 1/16W
J 2
(-1175 -575);
DISPLAY 0.638298 (-1175 -575);
DISPLAY INVISIBLE (-1175 -575);
FORCEPROP 0 LAST CDS_LOCATION R4097
J 0
(-1100 -650);
DISPLAY 1.021277 (-1100 -650);
DISPLAY INVISIBLE (-1100 -650);
FORCEPROP 0 LAST $SEC 1
J 0
(-1100 -650);
DISPLAY 0.680851 (-1100 -650);
PAINT MONO (-1100 -650);
DISPLAY INVISIBLE (-1100 -650);
FORCEPROP 0 LAST CDS_SEC 1
J 0
(-1100 -650);
DISPLAY 1.021277 (-1100 -650);
DISPLAY INVISIBLE (-1100 -650);
FORCEADD Q_RES..1
(-1425 -750);
FORCEPROP 1 LAST PART_NUMBER CS31002FB08
J 0
(-1575 -675);
DISPLAY 0.638298 (-1575 -675);
DISPLAY INVISIBLE (-1575 -675);
FORCEPROP 1 LAST VALUE 10K
J 2
(-1225 -750);
DISPLAY 0.638298 (-1225 -750);
FORCEPROP 1 LAST TOLERANCE 1%
J 0
(-1200 -750);
DISPLAY 0.638298 (-1200 -750);
FORCEPROP 1 LAST MATERIAL CHIP
J 0
(-1100 -750);
DISPLAY 0.638298 (-1100 -750);
FORCEPROP 1 LAST $LOCATION R4098
J 0
(-1625 -750);
DISPLAY 0.638298 (-1625 -750);
FORCEPROP 1 LASTPIN (-1525 -750) $PN 1
J 0
(-1513 -738);
DISPLAY 0.787234 (-1513 -738);
PAINT MONO (-1513 -738);
FORCEPROP 1 LASTPIN (-1325 -750) $PN 2
J 0
(-1363 -738);
DISPLAY 0.787234 (-1363 -738);
PAINT MONO (-1363 -738);
FORCEPROP 2 LAST CDS_LIB pure_quanta
J 0
(-1425 -750);
DISPLAY INVISIBLE (-1425 -750);
FORCEPROP 1 LAST PATH I287
J 0
(-1475 -600);
DISPLAY 0.978723 (-1475 -600);
PAINT WHITE (-1475 -600);
DISPLAY INVISIBLE (-1475 -600);
FORCEPROP 1 LAST PACK_TYPE 0402LF
J 0
(-1575 -625);
DISPLAY 0.638298 (-1575 -625);
DISPLAY INVISIBLE (-1575 -625);
FORCEPROP 1 LAST WATTAGE 1/16W
J 2
(-1175 -625);
DISPLAY 0.638298 (-1175 -625);
DISPLAY INVISIBLE (-1175 -625);
FORCEPROP 0 LAST CDS_LOCATION R4098
J 0
(-1100 -700);
DISPLAY 1.021277 (-1100 -700);
DISPLAY INVISIBLE (-1100 -700);
FORCEPROP 0 LAST $SEC 1
J 0
(-1100 -700);
DISPLAY 0.680851 (-1100 -700);
PAINT MONO (-1100 -700);
DISPLAY INVISIBLE (-1100 -700);
FORCEPROP 0 LAST CDS_SEC 1
J 0
(-1100 -700);
DISPLAY 1.021277 (-1100 -700);
DISPLAY INVISIBLE (-1100 -700);
FORCEADD Q_RES..1
(-1425 -800);
FORCEPROP 1 LAST PART_NUMBER CS31002FB08
J 0
(-1575 -725);
DISPLAY 0.638298 (-1575 -725);
DISPLAY INVISIBLE (-1575 -725);
FORCEPROP 1 LAST TOLERANCE 1%
J 0
(-1200 -800);
DISPLAY 0.638298 (-1200 -800);
FORCEPROP 1 LAST VALUE 10K
J 2
(-1225 -800);
DISPLAY 0.638298 (-1225 -800);
FORCEPROP 1 LAST MATERIAL CHIP
J 0
(-1100 -800);
DISPLAY 0.638298 (-1100 -800);
FORCEPROP 1 LAST $LOCATION R4099
J 0
(-1625 -800);
DISPLAY 0.638298 (-1625 -800);
FORCEPROP 1 LASTPIN (-1525 -800) $PN 1
J 0
(-1513 -788);
DISPLAY 0.787234 (-1513 -788);
PAINT MONO (-1513 -788);
FORCEPROP 1 LASTPIN (-1325 -800) $PN 2
J 0
(-1363 -788);
DISPLAY 0.787234 (-1363 -788);
PAINT MONO (-1363 -788);
FORCEPROP 2 LAST CDS_LIB pure_quanta
J 0
(-1425 -800);
DISPLAY INVISIBLE (-1425 -800);
FORCEPROP 1 LAST PATH I288
J 0
(-1475 -650);
DISPLAY 0.978723 (-1475 -650);
PAINT WHITE (-1475 -650);
DISPLAY INVISIBLE (-1475 -650);
FORCEPROP 1 LAST WATTAGE 1/16W
J 2
(-1175 -675);
DISPLAY 0.638298 (-1175 -675);
DISPLAY INVISIBLE (-1175 -675);
FORCEPROP 1 LAST PACK_TYPE 0402LF
J 0
(-1575 -675);
DISPLAY 0.638298 (-1575 -675);
DISPLAY INVISIBLE (-1575 -675);
FORCEPROP 0 LAST CDS_LOCATION R4099
J 0
(-1100 -750);
DISPLAY 1.021277 (-1100 -750);
DISPLAY INVISIBLE (-1100 -750);
FORCEPROP 0 LAST $SEC 1
J 0
(-1100 -750);
DISPLAY 0.680851 (-1100 -750);
PAINT MONO (-1100 -750);
DISPLAY INVISIBLE (-1100 -750);
FORCEPROP 0 LAST CDS_SEC 1
J 0
(-1100 -750);
DISPLAY 1.021277 (-1100 -750);
DISPLAY INVISIBLE (-1100 -750);
FORCEADD UNIVERSAL_GND..1
(-900 -1050);
FORCEPROP 3 LASTPIN (-900 -1000) SIG_NAME GND\g
J 0
(-890 -990);
DISPLAY 0.659574 (-890 -990);
PAINT MONO (-890 -990);
DISPLAY INVISIBLE (-890 -990);
FORCEPROP 1 LAST HDL_POWER GND
J 1
(-875 -1125);
DISPLAY 0.872340 (-875 -1125);
PAINT GREEN (-875 -1125);
DISPLAY INVISIBLE (-875 -1125);
FORCEPROP 1 LAST PATH I289
J 0
(-825 -1050);
DISPLAY 0.872340 (-825 -1050);
PAINT AQUA (-825 -1050);
DISPLAY INVISIBLE (-825 -1050);
FORCEPROP 2 LAST CDS_LIB logical_power
J 0
(-900 -1050);
DISPLAY INVISIBLE (-900 -1050);
FORCEADD OFFPAGE..5
(-1925 2200);
FORCEPROP 2 LAST $XR0 131 
J 0
(-2180 2200);
DISPLAY 0.638298 (-2180 2200);
PAINT MONO (-2180 2200);
FORCEPROP 2 LAST PATH I29
J 0
(-1875 2275);
DISPLAY 1.021277 (-1875 2275);
DISPLAY INVISIBLE (-1875 2275);
FORCEPROP 1 LAST COMMENT_BODY TRUE
J 0
(-1825 2125);
DISPLAY 1.170213 (-1825 2125);
PAINT GREEN (-1825 2125);
DISPLAY INVISIBLE (-1825 2125);
FORCEPROP 1 LAST OFFPAGE TRUE
J 0
(-1600 2075);
DISPLAY 0.872340 (-1600 2075);
DISPLAY INVISIBLE (-1600 2075);
FORCEPROP 2 LAST CDS_LIB standard
J 0
(-1925 2200);
PAINT MONO (-1925 2200);
DISPLAY INVISIBLE (-1925 2200);
FORCEADD OFFPAGE..2
R 2
(-2500 -600);
FORCEPROP 2 LAST $XR0 183 
J 0
(-2785 -600);
DISPLAY 0.638298 (-2785 -600);
PAINT MONO (-2785 -600);
FORCEPROP 2 LAST CDS_LIB standard
J 2
(-2500 -600);
DISPLAY INVISIBLE (-2500 -600);
FORCEPROP 2 LAST PATH I290
J 2
(-2675 -525);
DISPLAY 1.021277 (-2675 -525);
DISPLAY INVISIBLE (-2675 -525);
FORCEPROP 1 LAST OFFPAGE TRUE
J 2
(-2825 -725);
DISPLAY 0.872340 (-2825 -725);
DISPLAY INVISIBLE (-2825 -725);
FORCEPROP 1 LAST COMMENT_BODY TRUE
J 2
(-2455 -695);
DISPLAY 0.872340 (-2455 -695);
PAINT GREEN (-2455 -695);
DISPLAY INVISIBLE (-2455 -695);
FORCEADD OFFPAGE..2
R 2
(-2500 -650);
FORCEPROP 2 LAST $XR0 183 
J 0
(-2785 -650);
DISPLAY 0.638298 (-2785 -650);
PAINT MONO (-2785 -650);
FORCEPROP 2 LAST CDS_LIB standard
J 0
(-2500 -650);
DISPLAY INVISIBLE (-2500 -650);
FORCEPROP 2 LAST PATH I291
J 0
(-2450 -575);
DISPLAY 1.021277 (-2450 -575);
DISPLAY INVISIBLE (-2450 -575);
FORCEPROP 1 LAST OFFPAGE TRUE
J 2
(-2825 -775);
DISPLAY 0.872340 (-2825 -775);
DISPLAY INVISIBLE (-2825 -775);
FORCEPROP 1 LAST COMMENT_BODY TRUE
J 2
(-2455 -745);
DISPLAY 0.872340 (-2455 -745);
PAINT GREEN (-2455 -745);
DISPLAY INVISIBLE (-2455 -745);
FORCEADD OFFPAGE..2
R 2
(-2500 -700);
FORCEPROP 2 LAST $XR0 183 
J 0
(-2785 -700);
DISPLAY 0.638298 (-2785 -700);
PAINT MONO (-2785 -700);
FORCEPROP 2 LAST CDS_LIB standard
J 0
(-2500 -700);
DISPLAY INVISIBLE (-2500 -700);
FORCEPROP 2 LAST PATH I292
J 0
(-2450 -625);
DISPLAY 1.021277 (-2450 -625);
DISPLAY INVISIBLE (-2450 -625);
FORCEPROP 1 LAST COMMENT_BODY TRUE
J 2
(-2455 -795);
DISPLAY 0.872340 (-2455 -795);
PAINT GREEN (-2455 -795);
DISPLAY INVISIBLE (-2455 -795);
FORCEPROP 1 LAST OFFPAGE TRUE
J 2
(-2825 -825);
DISPLAY 0.872340 (-2825 -825);
DISPLAY INVISIBLE (-2825 -825);
FORCEADD OFFPAGE..2
R 2
(-2500 -750);
FORCEPROP 2 LAST $XR0 183 
J 0
(-2785 -750);
DISPLAY 0.638298 (-2785 -750);
PAINT MONO (-2785 -750);
FORCEPROP 2 LAST CDS_LIB standard
J 0
(-2500 -750);
DISPLAY INVISIBLE (-2500 -750);
FORCEPROP 2 LAST PATH I293
J 0
(-2450 -675);
DISPLAY 1.021277 (-2450 -675);
DISPLAY INVISIBLE (-2450 -675);
FORCEPROP 1 LAST COMMENT_BODY TRUE
J 2
(-2455 -845);
DISPLAY 0.872340 (-2455 -845);
PAINT GREEN (-2455 -845);
DISPLAY INVISIBLE (-2455 -845);
FORCEPROP 1 LAST OFFPAGE TRUE
J 2
(-2825 -875);
DISPLAY 0.872340 (-2825 -875);
DISPLAY INVISIBLE (-2825 -875);
FORCEADD OFFPAGE..2
R 2
(-2500 -800);
FORCEPROP 2 LAST $XR0 183 
J 0
(-2785 -800);
DISPLAY 0.638298 (-2785 -800);
PAINT MONO (-2785 -800);
FORCEPROP 2 LAST CDS_LIB standard
J 0
(-2500 -800);
DISPLAY INVISIBLE (-2500 -800);
FORCEPROP 2 LAST PATH I294
J 0
(-2450 -725);
DISPLAY 1.021277 (-2450 -725);
DISPLAY INVISIBLE (-2450 -725);
FORCEPROP 1 LAST COMMENT_BODY TRUE
J 2
(-2455 -895);
DISPLAY 0.872340 (-2455 -895);
PAINT GREEN (-2455 -895);
DISPLAY INVISIBLE (-2455 -895);
FORCEPROP 1 LAST OFFPAGE TRUE
J 2
(-2825 -925);
DISPLAY 0.872340 (-2825 -925);
DISPLAY INVISIBLE (-2825 -925);
FORCEADD OFFPAGE..1
R 2
(4450 3750);
FORCEPROP 2 LAST $XR0 183 
J 0
(4636 3750);
DISPLAY 0.638298 (4636 3750);
PAINT MONO (4636 3750);
FORCEPROP 1 LAST COMMENT_BODY TRUE
J 2
(4325 3650);
DISPLAY 0.872340 (4325 3650);
PAINT GREEN (4325 3650);
DISPLAY INVISIBLE (4325 3650);
FORCEPROP 1 LAST OFFPAGE TRUE
J 2
(4125 3625);
DISPLAY 0.872340 (4125 3625);
DISPLAY INVISIBLE (4125 3625);
FORCEPROP 2 LAST PATH I295
J 0
(4625 3825);
DISPLAY 1.021277 (4625 3825);
DISPLAY INVISIBLE (4625 3825);
FORCEPROP 2 LAST CDS_LIB standard
J 0
(4450 3750);
DISPLAY INVISIBLE (4450 3750);
FORCEADD OFFPAGE..1
R 2
(4450 3700);
FORCEPROP 2 LAST $XR0 183 
J 0
(4636 3700);
DISPLAY 0.638298 (4636 3700);
PAINT MONO (4636 3700);
FORCEPROP 1 LAST OFFPAGE TRUE
J 2
(4125 3575);
DISPLAY 0.872340 (4125 3575);
DISPLAY INVISIBLE (4125 3575);
FORCEPROP 1 LAST COMMENT_BODY TRUE
J 2
(4325 3600);
DISPLAY 0.872340 (4325 3600);
PAINT GREEN (4325 3600);
DISPLAY INVISIBLE (4325 3600);
FORCEPROP 2 LAST PATH I296
J 0
(4625 3775);
DISPLAY 1.021277 (4625 3775);
DISPLAY INVISIBLE (4625 3775);
FORCEPROP 2 LAST CDS_LIB standard
J 0
(4450 3700);
DISPLAY INVISIBLE (4450 3700);
FORCEADD OFFPAGE..1
R 2
(4450 3500);
FORCEPROP 2 LAST $XR0 183 
J 0
(4636 3500);
DISPLAY 0.638298 (4636 3500);
PAINT MONO (4636 3500);
FORCEPROP 1 LAST OFFPAGE TRUE
J 2
(4125 3375);
DISPLAY 0.872340 (4125 3375);
DISPLAY INVISIBLE (4125 3375);
FORCEPROP 1 LAST COMMENT_BODY TRUE
J 2
(4325 3400);
DISPLAY 0.872340 (4325 3400);
PAINT GREEN (4325 3400);
DISPLAY INVISIBLE (4325 3400);
FORCEPROP 2 LAST PATH I297
J 0
(4625 3575);
DISPLAY 1.021277 (4625 3575);
DISPLAY INVISIBLE (4625 3575);
FORCEPROP 2 LAST CDS_LIB standard
J 0
(4450 3500);
DISPLAY INVISIBLE (4450 3500);
FORCEADD Q_RES..1
(-1425 -950);
FORCEPROP 1 LAST PART_NUMBER CS31002FB08
J 0
(-1575 -875);
DISPLAY 0.638298 (-1575 -875);
DISPLAY INVISIBLE (-1575 -875);
FORCEPROP 1 LAST TOLERANCE 1%
J 0
(-1200 -950);
DISPLAY 0.638298 (-1200 -950);
FORCEPROP 1 LAST VALUE 10K
J 2
(-1225 -950);
DISPLAY 0.638298 (-1225 -950);
FORCEPROP 1 LAST MATERIAL CHIP
J 0
(-1100 -950);
DISPLAY 0.638298 (-1100 -950);
FORCEPROP 1 LAST $LOCATION R4102
J 0
(-1625 -950);
DISPLAY 0.638298 (-1625 -950);
FORCEPROP 1 LASTPIN (-1525 -950) $PN 1
J 0
(-1513 -938);
DISPLAY 0.787234 (-1513 -938);
PAINT MONO (-1513 -938);
FORCEPROP 1 LASTPIN (-1325 -950) $PN 2
J 0
(-1363 -938);
DISPLAY 0.787234 (-1363 -938);
PAINT MONO (-1363 -938);
FORCEPROP 2 LAST CDS_LIB pure_quanta
J 0
(-1425 -950);
DISPLAY INVISIBLE (-1425 -950);
FORCEPROP 1 LAST PATH I298
J 0
(-1475 -800);
DISPLAY 0.978723 (-1475 -800);
PAINT WHITE (-1475 -800);
DISPLAY INVISIBLE (-1475 -800);
FORCEPROP 1 LAST PACK_TYPE 0402LF
J 0
(-1575 -825);
DISPLAY 0.638298 (-1575 -825);
DISPLAY INVISIBLE (-1575 -825);
FORCEPROP 1 LAST WATTAGE 1/16W
J 2
(-1175 -825);
DISPLAY 0.638298 (-1175 -825);
DISPLAY INVISIBLE (-1175 -825);
FORCEPROP 0 LAST CDS_LOCATION R4102
J 0
(-1100 -900);
DISPLAY 1.021277 (-1100 -900);
DISPLAY INVISIBLE (-1100 -900);
FORCEPROP 0 LAST $SEC 1
J 0
(-1100 -900);
DISPLAY 0.680851 (-1100 -900);
PAINT MONO (-1100 -900);
DISPLAY INVISIBLE (-1100 -900);
FORCEPROP 0 LAST CDS_SEC 1
J 0
(-1100 -900);
DISPLAY 1.021277 (-1100 -900);
DISPLAY INVISIBLE (-1100 -900);
FORCEADD Q_RES..1
(-1425 -900);
FORCEPROP 1 LAST PART_NUMBER CS31002FB08
J 0
(-1575 -825);
DISPLAY 0.638298 (-1575 -825);
DISPLAY INVISIBLE (-1575 -825);
FORCEPROP 1 LAST TOLERANCE 1%
J 0
(-1200 -900);
DISPLAY 0.638298 (-1200 -900);
FORCEPROP 1 LAST VALUE 10K
J 2
(-1225 -900);
DISPLAY 0.638298 (-1225 -900);
FORCEPROP 1 LAST MATERIAL CHIP
J 0
(-1100 -900);
DISPLAY 0.638298 (-1100 -900);
FORCEPROP 1 LAST $LOCATION R4101
J 0
(-1625 -900);
DISPLAY 0.638298 (-1625 -900);
FORCEPROP 1 LASTPIN (-1525 -900) $PN 1
J 0
(-1513 -888);
DISPLAY 0.787234 (-1513 -888);
PAINT MONO (-1513 -888);
FORCEPROP 1 LASTPIN (-1325 -900) $PN 2
J 0
(-1363 -888);
DISPLAY 0.787234 (-1363 -888);
PAINT MONO (-1363 -888);
FORCEPROP 1 LAST PACK_TYPE 0402LF
J 0
(-1575 -775);
DISPLAY 0.638298 (-1575 -775);
DISPLAY INVISIBLE (-1575 -775);
FORCEPROP 1 LAST WATTAGE 1/16W
J 2
(-1175 -775);
DISPLAY 0.638298 (-1175 -775);
DISPLAY INVISIBLE (-1175 -775);
FORCEPROP 1 LAST PATH I299
J 0
(-1475 -750);
DISPLAY 0.978723 (-1475 -750);
PAINT WHITE (-1475 -750);
DISPLAY INVISIBLE (-1475 -750);
FORCEPROP 2 LAST CDS_LIB pure_quanta
J 0
(-1425 -900);
DISPLAY INVISIBLE (-1425 -900);
FORCEPROP 0 LAST CDS_LOCATION R4101
J 0
(-1100 -850);
DISPLAY 1.021277 (-1100 -850);
DISPLAY INVISIBLE (-1100 -850);
FORCEPROP 0 LAST $SEC 1
J 0
(-1100 -850);
DISPLAY 0.680851 (-1100 -850);
PAINT MONO (-1100 -850);
DISPLAY INVISIBLE (-1100 -850);
FORCEPROP 0 LAST CDS_SEC 1
J 0
(-1100 -850);
DISPLAY 1.021277 (-1100 -850);
DISPLAY INVISIBLE (-1100 -850);
FORCEADD OFFPAGE..5
(-1925 2150);
FORCEPROP 2 LAST $XR0 131 
J 0
(-2180 2150);
DISPLAY 0.638298 (-2180 2150);
PAINT MONO (-2180 2150);
FORCEPROP 2 LAST PATH I30
J 0
(-1875 2225);
DISPLAY 1.021277 (-1875 2225);
DISPLAY INVISIBLE (-1875 2225);
FORCEPROP 1 LAST COMMENT_BODY TRUE
J 0
(-1825 2075);
DISPLAY 1.170213 (-1825 2075);
PAINT GREEN (-1825 2075);
DISPLAY INVISIBLE (-1825 2075);
FORCEPROP 1 LAST OFFPAGE TRUE
J 0
(-1600 2025);
DISPLAY 0.872340 (-1600 2025);
DISPLAY INVISIBLE (-1600 2025);
FORCEPROP 2 LAST CDS_LIB standard
J 0
(-1925 2150);
PAINT MONO (-1925 2150);
DISPLAY INVISIBLE (-1925 2150);
FORCEADD Q_RES..1
(-1425 -850);
FORCEPROP 1 LAST PART_NUMBER CS31002FB08
J 0
(-1575 -775);
DISPLAY 0.638298 (-1575 -775);
DISPLAY INVISIBLE (-1575 -775);
FORCEPROP 1 LAST MATERIAL CHIP
J 0
(-1100 -850);
DISPLAY 0.638298 (-1100 -850);
FORCEPROP 1 LAST TOLERANCE 1%
J 0
(-1200 -850);
DISPLAY 0.638298 (-1200 -850);
FORCEPROP 1 LAST VALUE 10K
J 2
(-1225 -850);
DISPLAY 0.638298 (-1225 -850);
FORCEPROP 1 LAST $LOCATION R4100
J 0
(-1625 -850);
DISPLAY 0.638298 (-1625 -850);
FORCEPROP 1 LASTPIN (-1525 -850) $PN 1
J 0
(-1513 -838);
DISPLAY 0.787234 (-1513 -838);
PAINT MONO (-1513 -838);
FORCEPROP 1 LASTPIN (-1325 -850) $PN 2
J 0
(-1363 -838);
DISPLAY 0.787234 (-1363 -838);
PAINT MONO (-1363 -838);
FORCEPROP 1 LAST PACK_TYPE 0402LF
J 0
(-1575 -725);
DISPLAY 0.638298 (-1575 -725);
DISPLAY INVISIBLE (-1575 -725);
FORCEPROP 1 LAST WATTAGE 1/16W
J 2
(-1175 -725);
DISPLAY 0.638298 (-1175 -725);
DISPLAY INVISIBLE (-1175 -725);
FORCEPROP 1 LAST PATH I300
J 0
(-1475 -700);
DISPLAY 0.978723 (-1475 -700);
PAINT WHITE (-1475 -700);
DISPLAY INVISIBLE (-1475 -700);
FORCEPROP 2 LAST CDS_LIB pure_quanta
J 0
(-1425 -850);
DISPLAY INVISIBLE (-1425 -850);
FORCEPROP 0 LAST CDS_LOCATION R4100
J 0
(-1100 -800);
DISPLAY 1.021277 (-1100 -800);
DISPLAY INVISIBLE (-1100 -800);
FORCEPROP 0 LAST $SEC 1
J 0
(-1100 -800);
DISPLAY 0.680851 (-1100 -800);
PAINT MONO (-1100 -800);
DISPLAY INVISIBLE (-1100 -800);
FORCEPROP 0 LAST CDS_SEC 1
J 0
(-1100 -800);
DISPLAY 1.021277 (-1100 -800);
DISPLAY INVISIBLE (-1100 -800);
FORCEADD OFFPAGE..2
R 2
(-2500 -950);
FORCEPROP 2 LAST $XR0 183 
J 0
(-2785 -950);
DISPLAY 0.638298 (-2785 -950);
PAINT MONO (-2785 -950);
FORCEPROP 1 LAST OFFPAGE TRUE
J 2
(-2825 -1075);
DISPLAY 0.872340 (-2825 -1075);
DISPLAY INVISIBLE (-2825 -1075);
FORCEPROP 1 LAST COMMENT_BODY TRUE
J 2
(-2455 -1045);
DISPLAY 0.872340 (-2455 -1045);
PAINT GREEN (-2455 -1045);
DISPLAY INVISIBLE (-2455 -1045);
FORCEPROP 2 LAST PATH I302
J 0
(-2450 -875);
DISPLAY 1.021277 (-2450 -875);
DISPLAY INVISIBLE (-2450 -875);
FORCEPROP 2 LAST CDS_LIB standard
J 0
(-2500 -950);
DISPLAY INVISIBLE (-2500 -950);
FORCEADD OFFPAGE..2
R 2
(-2500 -900);
FORCEPROP 2 LAST $XR0 183 
J 0
(-2785 -900);
DISPLAY 0.638298 (-2785 -900);
PAINT MONO (-2785 -900);
FORCEPROP 1 LAST OFFPAGE TRUE
J 2
(-2825 -1025);
DISPLAY 0.872340 (-2825 -1025);
DISPLAY INVISIBLE (-2825 -1025);
FORCEPROP 1 LAST COMMENT_BODY TRUE
J 2
(-2455 -995);
DISPLAY 0.872340 (-2455 -995);
PAINT GREEN (-2455 -995);
DISPLAY INVISIBLE (-2455 -995);
FORCEPROP 2 LAST PATH I303
J 0
(-2450 -825);
DISPLAY 1.021277 (-2450 -825);
DISPLAY INVISIBLE (-2450 -825);
FORCEPROP 2 LAST CDS_LIB standard
J 0
(-2500 -900);
DISPLAY INVISIBLE (-2500 -900);
FORCEADD OFFPAGE..2
R 2
(-2500 -850);
FORCEPROP 2 LAST $XR0 183 
J 0
(-2785 -850);
DISPLAY 0.638298 (-2785 -850);
PAINT MONO (-2785 -850);
FORCEPROP 1 LAST COMMENT_BODY TRUE
J 2
(-2455 -945);
DISPLAY 0.872340 (-2455 -945);
PAINT GREEN (-2455 -945);
DISPLAY INVISIBLE (-2455 -945);
FORCEPROP 1 LAST OFFPAGE TRUE
J 2
(-2825 -975);
DISPLAY 0.872340 (-2825 -975);
DISPLAY INVISIBLE (-2825 -975);
FORCEPROP 2 LAST PATH I304
J 0
(-2450 -775);
DISPLAY 1.021277 (-2450 -775);
DISPLAY INVISIBLE (-2450 -775);
FORCEPROP 2 LAST CDS_LIB standard
J 0
(-2500 -850);
DISPLAY INVISIBLE (-2500 -850);
FORCEADD Q_RES..1
(2950 1450);
FORCEPROP 1 LAST PART_NUMBER CS03322FB03
J 0
(2850 1525);
DISPLAY 0.404255 (2850 1525);
DISPLAY INVISIBLE (2850 1525);
FORCEPROP 1 LAST VALUE 33.2
J 2
(3150 1450);
DISPLAY 0.510638 (3150 1450);
FORCEPROP 1 LAST MATERIAL CHIP
J 0
(3200 1450);
DISPLAY 0.510638 (3200 1450);
FORCEPROP 1 LAST $LOCATION R4505
J 0
(2700 1450);
DISPLAY 0.638298 (2700 1450);
FORCEPROP 1 LASTPIN (2850 1450) $PN 1
J 0
(2862 1462);
DISPLAY 0.787234 (2862 1462);
PAINT MONO (2862 1462);
FORCEPROP 1 LASTPIN (3050 1450) $PN 2
J 0
(3012 1462);
DISPLAY 0.787234 (3012 1462);
PAINT MONO (3012 1462);
FORCEPROP 1 LAST PATH I305
J 0
(2900 1600);
DISPLAY 0.978723 (2900 1600);
PAINT WHITE (2900 1600);
DISPLAY INVISIBLE (2900 1600);
FORCEPROP 1 LAST WATTAGE 1/16W
J 2
(3100 1550);
DISPLAY 0.404255 (3100 1550);
DISPLAY INVISIBLE (3100 1550);
FORCEPROP 1 LAST TOLERANCE 1%
J 0
(3175 1450);
DISPLAY 0.510638 (3175 1450);
DISPLAY INVISIBLE (3175 1450);
FORCEPROP 1 LAST PACK_TYPE 0402LF
J 0
(2850 1550);
DISPLAY 0.404255 (2850 1550);
DISPLAY INVISIBLE (2850 1550);
FORCEPROP 2 LAST CDS_LIB pure_quanta
J 0
(2950 1450);
DISPLAY INVISIBLE (2950 1450);
FORCEPROP 0 LAST CDS_LOCATION R4505
J 0
(2775 1500);
DISPLAY 1.021277 (2775 1500);
DISPLAY INVISIBLE (2775 1500);
FORCEPROP 0 LAST $SEC 1
J 0
(2775 1500);
DISPLAY 0.680851 (2775 1500);
PAINT MONO (2775 1500);
DISPLAY INVISIBLE (2775 1500);
FORCEPROP 0 LAST CDS_SEC 1
J 0
(2775 1500);
DISPLAY 1.021277 (2775 1500);
DISPLAY INVISIBLE (2775 1500);
FORCEADD OFFPAGE..3
(4475 1500);
FORCEPROP 2 LAST $XR0 183 
J 0
(4689 1500);
DISPLAY 0.638298 (4689 1500);
PAINT MONO (4689 1500);
FORCEPROP 2 LAST PATH I306
J 0
(4950 1550);
DISPLAY 1.021277 (4950 1550);
DISPLAY INVISIBLE (4950 1550);
FORCEPROP 1 LAST OFFPAGE TRUE
J 0
(4800 1375);
DISPLAY 0.872340 (4800 1375);
PAINT GREEN (4800 1375);
DISPLAY INVISIBLE (4800 1375);
FORCEPROP 1 LAST COMMENT_BODY TRUE
J 0
(4425 1400);
DISPLAY 0.872340 (4425 1400);
PAINT GREEN (4425 1400);
DISPLAY INVISIBLE (4425 1400);
FORCEPROP 2 LAST CDS_LIB standard
J 0
(4475 1500);
PAINT MONO (4475 1500);
DISPLAY INVISIBLE (4475 1500);
FORCEADD OFFPAGE..2
(4475 1450);
FORCEPROP 2 LAST $XR0 183 
J 0
(4664 1450);
DISPLAY 0.638298 (4664 1450);
PAINT MONO (4664 1450);
FORCEPROP 2 LAST PATH I307
J 0
(4950 1500);
DISPLAY 1.021277 (4950 1500);
DISPLAY INVISIBLE (4950 1500);
FORCEPROP 1 LAST OFFPAGE TRUE
J 0
(4800 1325);
DISPLAY 0.872340 (4800 1325);
PAINT GREEN (4800 1325);
DISPLAY INVISIBLE (4800 1325);
FORCEPROP 1 LAST COMMENT_BODY TRUE
J 0
(4430 1355);
DISPLAY 0.872340 (4430 1355);
PAINT GREEN (4430 1355);
DISPLAY INVISIBLE (4430 1355);
FORCEPROP 2 LAST CDS_LIB standard
J 0
(4475 1450);
PAINT MONO (4475 1450);
DISPLAY INVISIBLE (4475 1450);
FORCEADD Q_RES..1
(2950 1500);
FORCEPROP 1 LAST PART_NUMBER CS00002JB13
J 0
(2850 1550);
DISPLAY 0.404255 (2850 1550);
DISPLAY INVISIBLE (2850 1550);
FORCEPROP 1 LAST MATERIAL CHIP
J 0
(3200 1500);
DISPLAY 0.510638 (3200 1500);
FORCEPROP 1 LAST VALUE 0
J 2
(3100 1500);
DISPLAY 0.510638 (3100 1500);
FORCEPROP 1 LAST $LOCATION R4504
J 0
(2700 1500);
DISPLAY 0.638298 (2700 1500);
FORCEPROP 1 LASTPIN (2850 1500) $PN 1
J 0
(2862 1512);
DISPLAY 0.787234 (2862 1512);
PAINT MONO (2862 1512);
FORCEPROP 1 LASTPIN (3050 1500) $PN 2
J 0
(3012 1512);
DISPLAY 0.787234 (3012 1512);
PAINT MONO (3012 1512);
FORCEPROP 1 LAST PATH I308
J 0
(2900 1650);
DISPLAY 0.978723 (2900 1650);
PAINT WHITE (2900 1650);
DISPLAY INVISIBLE (2900 1650);
FORCEPROP 1 LAST WATTAGE 1/16W
J 2
(3100 1575);
DISPLAY 0.404255 (3100 1575);
DISPLAY INVISIBLE (3100 1575);
FORCEPROP 1 LAST TOLERANCE 5%
J 0
(3125 1500);
DISPLAY 0.510638 (3125 1500);
DISPLAY INVISIBLE (3125 1500);
FORCEPROP 1 LAST PACK_TYPE 0402LF
J 0
(2850 1575);
DISPLAY 0.404255 (2850 1575);
DISPLAY INVISIBLE (2850 1575);
FORCEPROP 2 LAST CDS_LIB pure_quanta
J 0
(2950 1500);
DISPLAY INVISIBLE (2950 1500);
FORCEPROP 0 LAST CDS_LOCATION R4504
J 0
(2775 1550);
DISPLAY 1.021277 (2775 1550);
DISPLAY INVISIBLE (2775 1550);
FORCEPROP 0 LAST $SEC 1
J 0
(2775 1550);
DISPLAY 0.680851 (2775 1550);
PAINT MONO (2775 1550);
DISPLAY INVISIBLE (2775 1550);
FORCEPROP 0 LAST CDS_SEC 1
J 0
(2775 1550);
DISPLAY 1.021277 (2775 1550);
DISPLAY INVISIBLE (2775 1550);
FORCEADD OFFPAGE..1
(1575 1450);
FORCEPROP 2 LAST $XR1 241 
J 0
(1173 1450);
DISPLAY 0.638298 (1173 1450);
PAINT MONO (1173 1450);
FORCEPROP 2 LAST $XR0 240 
J 0
(1293 1450);
DISPLAY 0.638298 (1293 1450);
PAINT MONO (1293 1450);
FORCEPROP 2 LAST CDS_LIB standard
J 0
(1575 1450);
DISPLAY INVISIBLE (1575 1450);
FORCEPROP 2 LAST PATH I309
J 0
(1625 1525);
DISPLAY 1.021277 (1625 1525);
DISPLAY INVISIBLE (1625 1525);
FORCEPROP 1 LAST OFFPAGE TRUE
J 0
(1900 1325);
DISPLAY 0.872340 (1900 1325);
DISPLAY INVISIBLE (1900 1325);
FORCEPROP 1 LAST COMMENT_BODY TRUE
J 0
(1700 1350);
DISPLAY 0.872340 (1700 1350);
PAINT GREEN (1700 1350);
DISPLAY INVISIBLE (1700 1350);
FORCEADD OFFPAGE..5
(-1925 2350);
FORCEPROP 2 LAST $XR0 131 
J 0
(-2180 2350);
DISPLAY 0.638298 (-2180 2350);
PAINT MONO (-2180 2350);
FORCEPROP 2 LAST PATH I31
J 0
(-1875 2425);
DISPLAY 1.021277 (-1875 2425);
DISPLAY INVISIBLE (-1875 2425);
FORCEPROP 1 LAST COMMENT_BODY TRUE
J 0
(-1825 2275);
DISPLAY 1.170213 (-1825 2275);
PAINT GREEN (-1825 2275);
DISPLAY INVISIBLE (-1825 2275);
FORCEPROP 1 LAST OFFPAGE TRUE
J 0
(-1600 2225);
DISPLAY 0.872340 (-1600 2225);
DISPLAY INVISIBLE (-1600 2225);
FORCEPROP 2 LAST CDS_LIB standard
J 0
(-1925 2350);
PAINT MONO (-1925 2350);
DISPLAY INVISIBLE (-1925 2350);
FORCEADD OFFPAGE..3
R 2
(1575 1500);
FORCEPROP 2 LAST $XR1 241 
J 0
(1145 1500);
DISPLAY 0.638298 (1145 1500);
PAINT MONO (1145 1500);
FORCEPROP 2 LAST $XR0 240 
J 0
(1265 1500);
DISPLAY 0.638298 (1265 1500);
PAINT MONO (1265 1500);
FORCEPROP 1 LAST OFFPAGE TRUE
J 2
(1250 1375);
DISPLAY 0.872340 (1250 1375);
PAINT GREEN (1250 1375);
DISPLAY INVISIBLE (1250 1375);
FORCEPROP 1 LAST COMMENT_BODY TRUE
J 2
(1625 1400);
DISPLAY 0.872340 (1625 1400);
PAINT GREEN (1625 1400);
DISPLAY INVISIBLE (1625 1400);
FORCEPROP 2 LAST PATH I310
J 2
(1375 1575);
DISPLAY 1.021277 (1375 1575);
DISPLAY INVISIBLE (1375 1575);
FORCEPROP 2 LAST CDS_LIB standard
J 2
(1575 1500);
DISPLAY INVISIBLE (1575 1500);
FORCEADD OFFPAGE..1
(-1925 4150);
FORCEPROP 2 LAST $XR1 183 
J 0
(-2327 4150);
DISPLAY 0.638298 (-2327 4150);
PAINT MONO (-2327 4150);
FORCEPROP 2 LAST $XR0 194 
J 0
(-2207 4150);
DISPLAY 0.638298 (-2207 4150);
PAINT MONO (-2207 4150);
FORCEPROP 2 LAST CDS_LIB standard
J 0
(-1925 4150);
DISPLAY INVISIBLE (-1925 4150);
FORCEPROP 2 LAST PATH I311
J 0
(-1875 4225);
DISPLAY 1.021277 (-1875 4225);
DISPLAY INVISIBLE (-1875 4225);
FORCEPROP 1 LAST COMMENT_BODY TRUE
J 0
(-1800 4050);
DISPLAY 1.170213 (-1800 4050);
PAINT GREEN (-1800 4050);
DISPLAY INVISIBLE (-1800 4050);
FORCEPROP 1 LAST OFFPAGE TRUE
J 0
(-1600 4025);
DISPLAY 0.872340 (-1600 4025);
DISPLAY INVISIBLE (-1600 4025);
FORCEADD OFFPAGE..1
(-3600 3775);
FORCEPROP 2 LAST $XR1 216 
J 0
(-3882 3739);
DISPLAY 0.638298 (-3882 3739);
PAINT MONO (-3882 3739);
FORCEPROP 2 LAST $XR0 183 
J 0
(-3882 3775);
DISPLAY 0.638298 (-3882 3775);
PAINT MONO (-3882 3775);
FORCEPROP 1 LAST OFFPAGE TRUE
J 0
(-3275 3650);
DISPLAY 0.872340 (-3275 3650);
PAINT GREEN (-3275 3650);
DISPLAY INVISIBLE (-3275 3650);
FORCEPROP 1 LAST COMMENT_BODY TRUE
J 0
(-3475 3675);
DISPLAY 0.872340 (-3475 3675);
PAINT GREEN (-3475 3675);
DISPLAY INVISIBLE (-3475 3675);
FORCEPROP 2 LAST PATH I312
J 0
(-3550 3850);
DISPLAY 1.021277 (-3550 3850);
DISPLAY INVISIBLE (-3550 3850);
FORCEPROP 2 LAST CDS_LIB standard
J 0
(-3600 3775);
DISPLAY INVISIBLE (-3600 3775);
FORCEADD Q_RES..1
(-2700 3775);
FORCEPROP 1 LAST PART_NUMBER CS04992FB07
J 0
(-2600 3750);
DISPLAY 0.404255 (-2600 3750);
DISPLAY INVISIBLE (-2600 3750);
FORCEPROP 1 LAST MATERIAL CHIP
J 0
(-2850 3750);
DISPLAY 0.404255 (-2850 3750);
FORCEPROP 1 LAST VALUE 49.9
J 2
(-2475 3775);
DISPLAY 0.510638 (-2475 3775);
FORCEPROP 1 LAST LOCATION R4766
J 0
(-2900 3775);
DISPLAY 0.638298 (-2900 3775);
FORCEPROP 1 LASTPIN (-2800 3775) $PN 1
J 0
(-2788 3787);
DISPLAY 0.787234 (-2788 3787);
PAINT MONO (-2788 3787);
FORCEPROP 1 LASTPIN (-2600 3775) $PN 2
J 0
(-2638 3787);
DISPLAY 0.787234 (-2638 3787);
PAINT MONO (-2638 3787);
FORCEPROP 2 LAST CDS_LIB pure_quanta
J 0
(-2700 3775);
DISPLAY INVISIBLE (-2700 3775);
FORCEPROP 1 LAST PATH I314
J 0
(-2750 3925);
DISPLAY 0.978723 (-2750 3925);
PAINT WHITE (-2750 3925);
DISPLAY INVISIBLE (-2750 3925);
FORCEPROP 1 LAST WATTAGE 1/16W
J 2
(-2400 3725);
DISPLAY 0.404255 (-2400 3725);
DISPLAY INVISIBLE (-2400 3725);
FORCEPROP 1 LAST TOLERANCE 1%
J 0
(-2475 3775);
DISPLAY 0.510638 (-2475 3775);
DISPLAY INVISIBLE (-2475 3775);
FORCEPROP 1 LAST PACK_TYPE 0402LF
J 0
(-2400 3775);
DISPLAY 0.510638 (-2400 3775);
DISPLAY INVISIBLE (-2400 3775);
FORCEPROP 0 LAST $SEC 1
J 0
(-2900 3825);
DISPLAY 0.680851 (-2900 3825);
PAINT MONO (-2900 3825);
DISPLAY INVISIBLE (-2900 3825);
FORCEPROP 0 LAST CDS_SEC 1
J 0
(-2900 3825);
DISPLAY 1.021277 (-2900 3825);
DISPLAY INVISIBLE (-2900 3825);
FORCEADD Q_RES..1
(3475 -1350);
FORCEPROP 1 LAST PART_NUMBER CS31002FB08
J 0
(3325 -1450);
DISPLAY 0.638298 (3325 -1450);
DISPLAY INVISIBLE (3325 -1450);
FORCEPROP 1 LAST MATERIAL CHIP
J 0
(3800 -1350);
DISPLAY 0.638298 (3800 -1350);
FORCEPROP 1 LAST WATTAGE 1/16W
J 2
(3725 -1400);
DISPLAY 0.638298 (3725 -1400);
FORCEPROP 1 LAST PACK_TYPE 0402LF
J 0
(3325 -1400);
DISPLAY 0.638298 (3325 -1400);
FORCEPROP 1 LAST VALUE 10K
J 2
(3675 -1350);
DISPLAY 0.638298 (3675 -1350);
FORCEPROP 1 LAST TOLERANCE 1%
J 0
(3700 -1350);
DISPLAY 0.638298 (3700 -1350);
FORCEPROP 1 LAST $LOCATION R4768
J 0
(3175 -1350);
DISPLAY 0.787234 (3175 -1350);
FORCEPROP 1 LASTPIN (3375 -1350) $PN 1
J 0
(3387 -1338);
DISPLAY 0.787234 (3387 -1338);
PAINT MONO (3387 -1338);
FORCEPROP 1 LASTPIN (3575 -1350) $PN 2
J 0
(3537 -1338);
DISPLAY 0.787234 (3537 -1338);
PAINT MONO (3537 -1338);
FORCEPROP 2 LAST CDS_LIB pure_quanta
J 0
(3475 -1350);
DISPLAY INVISIBLE (3475 -1350);
FORCEPROP 1 LAST PATH I315
J 0
(3425 -1200);
DISPLAY 0.978723 (3425 -1200);
PAINT WHITE (3425 -1200);
DISPLAY INVISIBLE (3425 -1200);
FORCEPROP 0 LAST CDS_LOCATION R4768
J 0
(3800 -1300);
DISPLAY 1.021277 (3800 -1300);
DISPLAY INVISIBLE (3800 -1300);
FORCEPROP 0 LAST $SEC 1
J 0
(3800 -1300);
DISPLAY 0.680851 (3800 -1300);
PAINT MONO (3800 -1300);
DISPLAY INVISIBLE (3800 -1300);
FORCEPROP 0 LAST CDS_SEC 1
J 0
(3800 -1300);
DISPLAY 1.021277 (3800 -1300);
DISPLAY INVISIBLE (3800 -1300);
FORCEADD OFFPAGE..5
(1925 -1350);
FORCEPROP 2 LAST $XR1 183 
J 0
(1670 -1386);
DISPLAY 0.638298 (1670 -1386);
PAINT MONO (1670 -1386);
FORCEPROP 2 LAST $XR0 216 
J 0
(1670 -1350);
DISPLAY 0.638298 (1670 -1350);
PAINT MONO (1670 -1350);
FORCEPROP 2 LAST PATH I317
J 0
(1650 -1300);
DISPLAY 1.021277 (1650 -1300);
DISPLAY INVISIBLE (1650 -1300);
FORCEPROP 1 LAST COMMENT_BODY TRUE
J 0
(2025 -1425);
DISPLAY 1.170213 (2025 -1425);
PAINT GREEN (2025 -1425);
DISPLAY INVISIBLE (2025 -1425);
FORCEPROP 1 LAST OFFPAGE TRUE
J 0
(2250 -1475);
DISPLAY 0.872340 (2250 -1475);
DISPLAY INVISIBLE (2250 -1475);
FORCEPROP 2 LAST CDS_LIB standard
J 0
(1925 -1350);
DISPLAY INVISIBLE (1925 -1350);
FORCEADD OFFPAGE..5
(-1925 2100);
FORCEPROP 2 LAST $XR0 131 
J 0
(-2180 2100);
DISPLAY 0.638298 (-2180 2100);
PAINT MONO (-2180 2100);
FORCEPROP 1 LAST OFFPAGE TRUE
J 0
(-1600 1975);
DISPLAY 0.872340 (-1600 1975);
DISPLAY INVISIBLE (-1600 1975);
FORCEPROP 1 LAST COMMENT_BODY TRUE
J 0
(-1825 2025);
DISPLAY 1.170213 (-1825 2025);
PAINT GREEN (-1825 2025);
DISPLAY INVISIBLE (-1825 2025);
FORCEPROP 2 LAST PATH I32
J 0
(-1875 2175);
DISPLAY 1.021277 (-1875 2175);
DISPLAY INVISIBLE (-1875 2175);
FORCEPROP 2 LAST CDS_LIB standard
J 0
(-1925 2100);
PAINT MONO (-1925 2100);
DISPLAY INVISIBLE (-1925 2100);
FORCEADD OFFPAGE..1
(-1925 2400);
FORCEPROP 2 LAST $XR0 183 
J 0
(-2207 2400);
DISPLAY 0.638298 (-2207 2400);
PAINT MONO (-2207 2400);
FORCEPROP 2 LAST PATH I33
J 0
(-1875 2475);
DISPLAY 1.021277 (-1875 2475);
DISPLAY INVISIBLE (-1875 2475);
FORCEPROP 2 LAST CDS_LIB standard
J 0
(-1925 2400);
PAINT MONO (-1925 2400);
DISPLAY INVISIBLE (-1925 2400);
FORCEPROP 1 LAST OFFPAGE TRUE
J 0
(-1600 2275);
DISPLAY 0.872340 (-1600 2275);
DISPLAY INVISIBLE (-1600 2275);
FORCEPROP 1 LAST COMMENT_BODY TRUE
J 0
(-1800 2300);
DISPLAY 1.170213 (-1800 2300);
PAINT GREEN (-1800 2300);
DISPLAY INVISIBLE (-1800 2300);
FORCEADD OFFPAGE..3
R 2
(-1925 3600);
FORCEPROP 2 LAST $XR0 202 
J 0
(-2235 3600);
DISPLAY 0.638298 (-2235 3600);
PAINT MONO (-2235 3600);
FORCEPROP 2 LAST CDS_LIB standard
J 0
(-1925 3600);
PAINT MONO (-1925 3600);
DISPLAY INVISIBLE (-1925 3600);
FORCEPROP 2 LAST PATH I36
J 0
(-1875 3675);
DISPLAY 1.021277 (-1875 3675);
DISPLAY INVISIBLE (-1875 3675);
FORCEPROP 1 LAST COMMENT_BODY TRUE
J 2
(-1875 3500);
DISPLAY 0.872340 (-1875 3500);
PAINT GREEN (-1875 3500);
DISPLAY INVISIBLE (-1875 3500);
FORCEPROP 1 LAST OFFPAGE TRUE
J 2
(-2250 3475);
DISPLAY 0.872340 (-2250 3475);
DISPLAY INVISIBLE (-2250 3475);
FORCEADD OFFPAGE..3
R 2
(-1925 3550);
FORCEPROP 2 LAST $XR0 202 
J 0
(-2235 3550);
DISPLAY 0.638298 (-2235 3550);
PAINT MONO (-2235 3550);
FORCEPROP 2 LAST CDS_LIB standard
J 0
(-1925 3550);
PAINT MONO (-1925 3550);
DISPLAY INVISIBLE (-1925 3550);
FORCEPROP 2 LAST PATH I37
J 0
(-1875 3625);
DISPLAY 1.021277 (-1875 3625);
DISPLAY INVISIBLE (-1875 3625);
FORCEPROP 1 LAST COMMENT_BODY TRUE
J 2
(-1875 3450);
DISPLAY 0.872340 (-1875 3450);
PAINT GREEN (-1875 3450);
DISPLAY INVISIBLE (-1875 3450);
FORCEPROP 1 LAST OFFPAGE TRUE
J 2
(-2250 3425);
DISPLAY 0.872340 (-2250 3425);
DISPLAY INVISIBLE (-2250 3425);
FORCEADD OFFPAGE..3
R 2
(-1925 3500);
FORCEPROP 2 LAST $XR0 202 
J 0
(-2235 3500);
DISPLAY 0.638298 (-2235 3500);
PAINT MONO (-2235 3500);
FORCEPROP 2 LAST CDS_LIB standard
J 0
(-1925 3500);
PAINT MONO (-1925 3500);
DISPLAY INVISIBLE (-1925 3500);
FORCEPROP 2 LAST PATH I38
J 0
(-1875 3575);
DISPLAY 1.021277 (-1875 3575);
DISPLAY INVISIBLE (-1875 3575);
FORCEPROP 1 LAST OFFPAGE TRUE
J 2
(-2250 3375);
DISPLAY 0.872340 (-2250 3375);
DISPLAY INVISIBLE (-2250 3375);
FORCEPROP 1 LAST COMMENT_BODY TRUE
J 2
(-1875 3400);
DISPLAY 0.872340 (-1875 3400);
PAINT GREEN (-1875 3400);
DISPLAY INVISIBLE (-1875 3400);
FORCEADD OFFPAGE..3
R 2
(-1925 3450);
FORCEPROP 2 LAST $XR0 202 
J 0
(-2235 3450);
DISPLAY 0.638298 (-2235 3450);
PAINT MONO (-2235 3450);
FORCEPROP 2 LAST CDS_LIB standard
J 0
(-1925 3450);
PAINT MONO (-1925 3450);
DISPLAY INVISIBLE (-1925 3450);
FORCEPROP 2 LAST PATH I39
J 0
(-1875 3525);
DISPLAY 1.021277 (-1875 3525);
DISPLAY INVISIBLE (-1875 3525);
FORCEPROP 1 LAST OFFPAGE TRUE
J 2
(-2250 3325);
DISPLAY 0.872340 (-2250 3325);
DISPLAY INVISIBLE (-2250 3325);
FORCEPROP 1 LAST COMMENT_BODY TRUE
J 2
(-1875 3350);
DISPLAY 0.872340 (-1875 3350);
PAINT GREEN (-1875 3350);
DISPLAY INVISIBLE (-1875 3350);
FORCEADD OFFPAGE..5
(-1925 3650);
FORCEPROP 2 LAST $XR0 202 
J 0
(-2180 3650);
DISPLAY 0.638298 (-2180 3650);
PAINT MONO (-2180 3650);
FORCEPROP 2 LAST CDS_LIB standard
J 0
(-1925 3650);
PAINT MONO (-1925 3650);
DISPLAY INVISIBLE (-1925 3650);
FORCEPROP 2 LAST PATH I40
J 0
(-1875 3725);
DISPLAY 1.021277 (-1875 3725);
DISPLAY INVISIBLE (-1875 3725);
FORCEPROP 1 LAST OFFPAGE TRUE
J 0
(-1600 3525);
DISPLAY 0.872340 (-1600 3525);
DISPLAY INVISIBLE (-1600 3525);
FORCEPROP 1 LAST COMMENT_BODY TRUE
J 0
(-1825 3575);
DISPLAY 1.170213 (-1825 3575);
PAINT GREEN (-1825 3575);
DISPLAY INVISIBLE (-1825 3575);
FORCEADD OFFPAGE..5
(-1925 3700);
FORCEPROP 2 LAST $XR1 204 
J 0
(-2300 3700);
DISPLAY 0.638298 (-2300 3700);
PAINT MONO (-2300 3700);
FORCEPROP 2 LAST $XR0 202 
J 0
(-2180 3700);
DISPLAY 0.638298 (-2180 3700);
PAINT MONO (-2180 3700);
FORCEPROP 2 LAST PATH I41
J 0
(-1875 3775);
DISPLAY 1.021277 (-1875 3775);
DISPLAY INVISIBLE (-1875 3775);
FORCEPROP 2 LAST CDS_LIB standard
J 0
(-1925 3700);
PAINT MONO (-1925 3700);
DISPLAY INVISIBLE (-1925 3700);
FORCEPROP 1 LAST OFFPAGE TRUE
J 0
(-1600 3575);
DISPLAY 0.872340 (-1600 3575);
DISPLAY INVISIBLE (-1600 3575);
FORCEPROP 1 LAST COMMENT_BODY TRUE
J 0
(-1825 3625);
DISPLAY 1.170213 (-1825 3625);
PAINT GREEN (-1825 3625);
DISPLAY INVISIBLE (-1825 3625);
FORCEADD OFFPAGE..5
(-1925 3750);
FORCEPROP 2 LAST $XR0 202 
J 0
(-2180 3750);
DISPLAY 0.638298 (-2180 3750);
PAINT MONO (-2180 3750);
FORCEPROP 2 LAST CDS_LIB standard
J 0
(-1925 3750);
PAINT MONO (-1925 3750);
DISPLAY INVISIBLE (-1925 3750);
FORCEPROP 2 LAST PATH I42
J 0
(-1875 3825);
DISPLAY 1.021277 (-1875 3825);
DISPLAY INVISIBLE (-1875 3825);
FORCEPROP 1 LAST OFFPAGE TRUE
J 0
(-1600 3625);
DISPLAY 0.872340 (-1600 3625);
DISPLAY INVISIBLE (-1600 3625);
FORCEPROP 1 LAST COMMENT_BODY TRUE
J 0
(-1825 3675);
DISPLAY 1.170213 (-1825 3675);
PAINT GREEN (-1825 3675);
DISPLAY INVISIBLE (-1825 3675);
FORCEADD OFFPAGE..5
(-1925 3800);
FORCEPROP 2 LAST $XR0 202 
J 0
(-2180 3800);
DISPLAY 0.638298 (-2180 3800);
PAINT MONO (-2180 3800);
FORCEPROP 2 LAST CDS_LIB standard
J 0
(-1925 3800);
PAINT MONO (-1925 3800);
DISPLAY INVISIBLE (-1925 3800);
FORCEPROP 2 LAST PATH I43
J 0
(-1875 3875);
DISPLAY 1.021277 (-1875 3875);
DISPLAY INVISIBLE (-1875 3875);
FORCEPROP 1 LAST OFFPAGE TRUE
J 0
(-1600 3675);
DISPLAY 0.872340 (-1600 3675);
DISPLAY INVISIBLE (-1600 3675);
FORCEPROP 1 LAST COMMENT_BODY TRUE
J 0
(-1825 3725);
DISPLAY 1.170213 (-1825 3725);
PAINT GREEN (-1825 3725);
DISPLAY INVISIBLE (-1825 3725);
FORCEADD OFFPAGE..1
(-1925 4200);
FORCEPROP 2 LAST $XR0 183 
J 0
(-2207 4200);
DISPLAY 0.638298 (-2207 4200);
PAINT MONO (-2207 4200);
FORCEPROP 1 LAST OFFPAGE TRUE
J 0
(-1600 4075);
DISPLAY 0.872340 (-1600 4075);
DISPLAY INVISIBLE (-1600 4075);
FORCEPROP 1 LAST COMMENT_BODY TRUE
J 0
(-1800 4100);
DISPLAY 1.170213 (-1800 4100);
PAINT GREEN (-1800 4100);
DISPLAY INVISIBLE (-1800 4100);
FORCEPROP 2 LAST PATH I44
J 0
(-1875 4275);
DISPLAY 1.021277 (-1875 4275);
DISPLAY INVISIBLE (-1875 4275);
FORCEPROP 2 LAST CDS_LIB standard
J 0
(-1925 4200);
PAINT MONO (-1925 4200);
DISPLAY INVISIBLE (-1925 4200);
FORCEADD OFFPAGE..2
(4450 3250);
FORCEPROP 2 LAST $XR1 183 
J 0
(4789 3250);
DISPLAY 0.638298 (4789 3250);
PAINT MONO (4789 3250);
FORCEPROP 2 LAST $XR0 241 
J 0
(4669 3250);
DISPLAY 0.638298 (4669 3250);
PAINT MONO (4669 3250);
FORCEPROP 2 LAST CDS_LIB standard
J 0
(4450 3250);
PAINT MONO (4450 3250);
DISPLAY INVISIBLE (4450 3250);
FORCEPROP 1 LAST COMMENT_BODY TRUE
J 0
(4405 3155);
DISPLAY 0.872340 (4405 3155);
PAINT GREEN (4405 3155);
DISPLAY INVISIBLE (4405 3155);
FORCEPROP 1 LAST OFFPAGE TRUE
J 0
(4775 3125);
DISPLAY 0.872340 (4775 3125);
PAINT GREEN (4775 3125);
DISPLAY INVISIBLE (4775 3125);
FORCEPROP 2 LAST PATH I45
J 0
(4625 3325);
DISPLAY 1.021277 (4625 3325);
DISPLAY INVISIBLE (4625 3325);
FORCEADD OFFPAGE..3
(4450 3300);
FORCEPROP 2 LAST $XR1 241 
J 0
(4784 3300);
DISPLAY 0.638298 (4784 3300);
PAINT MONO (4784 3300);
FORCEPROP 2 LAST $XR0 183 
J 0
(4664 3300);
DISPLAY 0.638298 (4664 3300);
PAINT MONO (4664 3300);
FORCEPROP 1 LAST COMMENT_BODY TRUE
J 0
(4400 3200);
DISPLAY 0.872340 (4400 3200);
PAINT GREEN (4400 3200);
DISPLAY INVISIBLE (4400 3200);
FORCEPROP 1 LAST OFFPAGE TRUE
J 0
(4775 3175);
DISPLAY 0.872340 (4775 3175);
PAINT GREEN (4775 3175);
DISPLAY INVISIBLE (4775 3175);
FORCEPROP 2 LAST CDS_LIB standard
J 0
(4450 3300);
PAINT MONO (4450 3300);
DISPLAY INVISIBLE (4450 3300);
FORCEPROP 2 LAST PATH I46
J 0
(4650 3375);
DISPLAY 1.021277 (4650 3375);
DISPLAY INVISIBLE (4650 3375);
FORCEADD OFFPAGE..2
(4450 3550);
FORCEPROP 2 LAST $XR0 183 
J 0
(4669 3550);
DISPLAY 0.638298 (4669 3550);
PAINT MONO (4669 3550);
FORCEPROP 2 LAST CDS_LIB standard
J 0
(4450 3550);
PAINT MONO (4450 3550);
DISPLAY INVISIBLE (4450 3550);
FORCEPROP 1 LAST COMMENT_BODY TRUE
J 0
(4405 3455);
DISPLAY 0.872340 (4405 3455);
PAINT GREEN (4405 3455);
DISPLAY INVISIBLE (4405 3455);
FORCEPROP 1 LAST OFFPAGE TRUE
J 0
(4775 3425);
DISPLAY 0.872340 (4775 3425);
PAINT GREEN (4775 3425);
DISPLAY INVISIBLE (4775 3425);
FORCEPROP 2 LAST PATH I49
J 0
(4625 3625);
DISPLAY 1.021277 (4625 3625);
DISPLAY INVISIBLE (4625 3625);
FORCEADD OFFPAGE..3
(4450 3600);
FORCEPROP 2 LAST $XR0 183 
J 0
(4664 3600);
DISPLAY 0.638298 (4664 3600);
PAINT MONO (4664 3600);
FORCEPROP 2 LAST CDS_LIB standard
J 0
(4450 3600);
PAINT MONO (4450 3600);
DISPLAY INVISIBLE (4450 3600);
FORCEPROP 1 LAST COMMENT_BODY TRUE
J 0
(4400 3500);
DISPLAY 0.872340 (4400 3500);
PAINT GREEN (4400 3500);
DISPLAY INVISIBLE (4400 3500);
FORCEPROP 1 LAST OFFPAGE TRUE
J 0
(4775 3475);
DISPLAY 0.872340 (4775 3475);
PAINT GREEN (4775 3475);
DISPLAY INVISIBLE (4775 3475);
FORCEPROP 2 LAST PATH I50
J 0
(4650 3675);
DISPLAY 1.021277 (4650 3675);
DISPLAY INVISIBLE (4650 3675);
FORCEADD OFFPAGE..1
R 2
(4450 3650);
FORCEPROP 2 LAST $XR4 215 
J 0
(5116 3650);
DISPLAY 0.638298 (5116 3650);
PAINT MONO (5116 3650);
FORCEPROP 2 LAST $XR3 183 
J 0
(4996 3650);
DISPLAY 0.638298 (4996 3650);
PAINT MONO (4996 3650);
FORCEPROP 2 LAST $XR2 305 
J 0
(4876 3650);
DISPLAY 0.638298 (4876 3650);
PAINT MONO (4876 3650);
FORCEPROP 2 LAST $XR1 301 
J 0
(4756 3650);
DISPLAY 0.638298 (4756 3650);
PAINT MONO (4756 3650);
FORCEPROP 2 LAST $XR0 228 
J 0
(4636 3650);
DISPLAY 0.638298 (4636 3650);
PAINT MONO (4636 3650);
FORCEPROP 2 LAST CDS_LIB standard
J 0
(4450 3650);
PAINT MONO (4450 3650);
DISPLAY INVISIBLE (4450 3650);
FORCEPROP 2 LAST PATH I51
J 0
(4625 3725);
DISPLAY 1.021277 (4625 3725);
DISPLAY INVISIBLE (4625 3725);
FORCEPROP 1 LAST COMMENT_BODY TRUE
J 2
(4325 3550);
DISPLAY 0.872340 (4325 3550);
PAINT GREEN (4325 3550);
DISPLAY INVISIBLE (4325 3550);
FORCEPROP 1 LAST OFFPAGE TRUE
J 2
(4125 3525);
DISPLAY 0.872340 (4125 3525);
DISPLAY INVISIBLE (4125 3525);
FORCEADD OFFPAGE..1
R 2
(4450 3350);
FORCEPROP 2 LAST $XR0 183 
J 0
(4636 3350);
DISPLAY 0.638298 (4636 3350);
PAINT MONO (4636 3350);
FORCEPROP 2 LAST PATH I53
J 0
(4625 3425);
DISPLAY 1.021277 (4625 3425);
DISPLAY INVISIBLE (4625 3425);
FORCEPROP 1 LAST OFFPAGE TRUE
J 2
(4125 3225);
DISPLAY 0.872340 (4125 3225);
DISPLAY INVISIBLE (4125 3225);
FORCEPROP 1 LAST COMMENT_BODY TRUE
J 2
(4325 3250);
DISPLAY 0.872340 (4325 3250);
PAINT GREEN (4325 3250);
DISPLAY INVISIBLE (4325 3250);
FORCEPROP 2 LAST CDS_LIB standard
J 0
(4450 3350);
PAINT MONO (4450 3350);
DISPLAY INVISIBLE (4450 3350);
FORCEADD OFFPAGE..1
R 2
(4450 3800);
FORCEPROP 2 LAST $XR0 183 
J 0
(4636 3800);
DISPLAY 0.638298 (4636 3800);
PAINT MONO (4636 3800);
FORCEPROP 2 LAST CDS_LIB standard
J 0
(4450 3800);
PAINT MONO (4450 3800);
DISPLAY INVISIBLE (4450 3800);
FORCEPROP 2 LAST PATH I56
J 0
(4625 3875);
DISPLAY 1.021277 (4625 3875);
DISPLAY INVISIBLE (4625 3875);
FORCEPROP 1 LAST OFFPAGE TRUE
J 2
(4125 3675);
DISPLAY 0.872340 (4125 3675);
DISPLAY INVISIBLE (4125 3675);
FORCEPROP 1 LAST COMMENT_BODY TRUE
J 2
(4325 3700);
DISPLAY 0.872340 (4325 3700);
PAINT GREEN (4325 3700);
DISPLAY INVISIBLE (4325 3700);
FORCEADD OFFPAGE..1
R 2
(4450 3850);
FORCEPROP 2 LAST $XR0 183 
J 0
(4636 3850);
DISPLAY 0.638298 (4636 3850);
PAINT MONO (4636 3850);
FORCEPROP 2 LAST PATH I57
J 0
(4625 3925);
DISPLAY 1.021277 (4625 3925);
DISPLAY INVISIBLE (4625 3925);
FORCEPROP 1 LAST OFFPAGE TRUE
J 2
(4125 3725);
DISPLAY 0.872340 (4125 3725);
DISPLAY INVISIBLE (4125 3725);
FORCEPROP 1 LAST COMMENT_BODY TRUE
J 2
(4325 3750);
DISPLAY 0.872340 (4325 3750);
PAINT GREEN (4325 3750);
DISPLAY INVISIBLE (4325 3750);
FORCEPROP 2 LAST CDS_LIB standard
J 0
(4450 3850);
PAINT MONO (4450 3850);
DISPLAY INVISIBLE (4450 3850);
FORCEADD OFFPAGE..1
R 2
(4450 3900);
FORCEPROP 2 LAST $XR0 183 
J 0
(4636 3900);
DISPLAY 0.638298 (4636 3900);
PAINT MONO (4636 3900);
FORCEPROP 2 LAST PATH I58
J 0
(4625 3975);
DISPLAY 1.021277 (4625 3975);
DISPLAY INVISIBLE (4625 3975);
FORCEPROP 1 LAST COMMENT_BODY TRUE
J 2
(4325 3800);
DISPLAY 0.872340 (4325 3800);
PAINT GREEN (4325 3800);
DISPLAY INVISIBLE (4325 3800);
FORCEPROP 1 LAST OFFPAGE TRUE
J 2
(4125 3775);
DISPLAY 0.872340 (4125 3775);
DISPLAY INVISIBLE (4125 3775);
FORCEPROP 2 LAST CDS_LIB standard
J 0
(4450 3900);
PAINT MONO (4450 3900);
DISPLAY INVISIBLE (4450 3900);
FORCEADD OFFPAGE..1
R 2
(4450 4000);
FORCEPROP 2 LAST $XR0 183 
J 0
(4636 4000);
DISPLAY 0.638298 (4636 4000);
PAINT MONO (4636 4000);
FORCEPROP 2 LAST CDS_LIB standard
J 0
(4450 4000);
PAINT MONO (4450 4000);
DISPLAY INVISIBLE (4450 4000);
FORCEPROP 1 LAST COMMENT_BODY TRUE
J 2
(4325 3900);
DISPLAY 0.872340 (4325 3900);
PAINT GREEN (4325 3900);
DISPLAY INVISIBLE (4325 3900);
FORCEPROP 1 LAST OFFPAGE TRUE
J 2
(4125 3875);
DISPLAY 0.872340 (4125 3875);
DISPLAY INVISIBLE (4125 3875);
FORCEPROP 2 LAST PATH I60
J 0
(4625 4075);
DISPLAY 1.021277 (4625 4075);
DISPLAY INVISIBLE (4625 4075);
FORCEADD OFFPAGE..1
R 2
(4450 4050);
FORCEPROP 2 LAST $XR0 183 
J 0
(4636 4050);
DISPLAY 0.638298 (4636 4050);
PAINT MONO (4636 4050);
FORCEPROP 2 LAST CDS_LIB standard
J 0
(4450 4050);
PAINT MONO (4450 4050);
DISPLAY INVISIBLE (4450 4050);
FORCEPROP 1 LAST OFFPAGE TRUE
J 2
(4125 3925);
DISPLAY 0.872340 (4125 3925);
DISPLAY INVISIBLE (4125 3925);
FORCEPROP 1 LAST COMMENT_BODY TRUE
J 2
(4325 3950);
DISPLAY 0.872340 (4325 3950);
PAINT GREEN (4325 3950);
DISPLAY INVISIBLE (4325 3950);
FORCEPROP 2 LAST PATH I62
J 0
(4625 4125);
DISPLAY 1.021277 (4625 4125);
DISPLAY INVISIBLE (4625 4125);
FORCEADD OFFPAGE..2
(4450 3400);
FORCEPROP 2 LAST $XR0 183 
J 0
(4669 3400);
DISPLAY 0.638298 (4669 3400);
PAINT MONO (4669 3400);
FORCEPROP 2 LAST PATH I67
J 0
(4625 3475);
DISPLAY 1.021277 (4625 3475);
DISPLAY INVISIBLE (4625 3475);
FORCEPROP 1 LAST OFFPAGE TRUE
J 0
(4775 3275);
DISPLAY 0.872340 (4775 3275);
PAINT GREEN (4775 3275);
DISPLAY INVISIBLE (4775 3275);
FORCEPROP 1 LAST COMMENT_BODY TRUE
J 0
(4405 3305);
DISPLAY 0.872340 (4405 3305);
PAINT GREEN (4405 3305);
DISPLAY INVISIBLE (4405 3305);
FORCEPROP 2 LAST CDS_LIB standard
J 0
(4450 3400);
PAINT MONO (4450 3400);
DISPLAY INVISIBLE (4450 3400);
FORCEADD OFFPAGE..3
(4450 3450);
FORCEPROP 2 LAST $XR0 183 
J 0
(4664 3450);
DISPLAY 0.638298 (4664 3450);
PAINT MONO (4664 3450);
FORCEPROP 2 LAST PATH I68
J 0
(4650 3525);
DISPLAY 1.021277 (4650 3525);
DISPLAY INVISIBLE (4650 3525);
FORCEPROP 2 LAST CDS_LIB standard
J 0
(4450 3450);
PAINT MONO (4450 3450);
DISPLAY INVISIBLE (4450 3450);
FORCEPROP 1 LAST OFFPAGE TRUE
J 0
(4775 3325);
DISPLAY 0.872340 (4775 3325);
PAINT GREEN (4775 3325);
DISPLAY INVISIBLE (4775 3325);
FORCEPROP 1 LAST COMMENT_BODY TRUE
J 0
(4400 3350);
DISPLAY 0.872340 (4400 3350);
PAINT GREEN (4400 3350);
DISPLAY INVISIBLE (4400 3350);
FORCEADD OFFPAGE..2
(4450 4200);
FORCEPROP 2 LAST $XR0 183 
J 0
(4669 4200);
DISPLAY 0.638298 (4669 4200);
PAINT MONO (4669 4200);
FORCEPROP 2 LAST CDS_LIB standard
J 0
(4450 4200);
PAINT MONO (4450 4200);
DISPLAY INVISIBLE (4450 4200);
FORCEPROP 2 LAST PATH I70
J 0
(4625 4275);
DISPLAY 1.021277 (4625 4275);
DISPLAY INVISIBLE (4625 4275);
FORCEPROP 1 LAST COMMENT_BODY TRUE
J 0
(4405 4105);
DISPLAY 0.872340 (4405 4105);
PAINT GREEN (4405 4105);
DISPLAY INVISIBLE (4405 4105);
FORCEPROP 1 LAST OFFPAGE TRUE
J 0
(4775 4075);
DISPLAY 0.872340 (4775 4075);
PAINT GREEN (4775 4075);
DISPLAY INVISIBLE (4775 4075);
FORCEADD OFFPAGE..3
(4450 4250);
FORCEPROP 2 LAST $XR0 183 
J 0
(4664 4250);
DISPLAY 0.638298 (4664 4250);
PAINT MONO (4664 4250);
FORCEPROP 2 LAST PATH I71
J 0
(4650 4325);
DISPLAY 1.021277 (4650 4325);
DISPLAY INVISIBLE (4650 4325);
FORCEPROP 2 LAST CDS_LIB standard
J 0
(4450 4250);
PAINT MONO (4450 4250);
DISPLAY INVISIBLE (4450 4250);
FORCEPROP 1 LAST OFFPAGE TRUE
J 0
(4775 4125);
DISPLAY 0.872340 (4775 4125);
PAINT GREEN (4775 4125);
DISPLAY INVISIBLE (4775 4125);
FORCEPROP 1 LAST COMMENT_BODY TRUE
J 0
(4400 4150);
DISPLAY 0.872340 (4400 4150);
PAINT GREEN (4400 4150);
DISPLAY INVISIBLE (4400 4150);
FORCEADD OFFPAGE..1
R 2
(4450 4300);
FORCEPROP 2 LAST $XR0 183 
J 0
(4636 4300);
DISPLAY 0.638298 (4636 4300);
PAINT MONO (4636 4300);
FORCEPROP 2 LAST PATH I72
J 0
(4625 4375);
DISPLAY 1.021277 (4625 4375);
DISPLAY INVISIBLE (4625 4375);
FORCEPROP 1 LAST COMMENT_BODY TRUE
J 2
(4325 4200);
DISPLAY 0.872340 (4325 4200);
PAINT GREEN (4325 4200);
DISPLAY INVISIBLE (4325 4200);
FORCEPROP 1 LAST OFFPAGE TRUE
J 2
(4125 4175);
DISPLAY 0.872340 (4125 4175);
DISPLAY INVISIBLE (4125 4175);
FORCEPROP 2 LAST CDS_LIB standard
J 0
(4450 4300);
PAINT MONO (4450 4300);
DISPLAY INVISIBLE (4450 4300);
FORCEADD OFFPAGE..1
R 2
(4450 3150);
FORCEPROP 2 LAST $XR0 198 
J 0
(4636 3150);
DISPLAY 0.638298 (4636 3150);
PAINT MONO (4636 3150);
FORCEPROP 1 LAST OFFPAGE TRUE
J 2
(4125 3025);
DISPLAY 0.872340 (4125 3025);
DISPLAY INVISIBLE (4125 3025);
FORCEPROP 1 LAST COMMENT_BODY TRUE
J 2
(4325 3050);
DISPLAY 0.872340 (4325 3050);
PAINT GREEN (4325 3050);
DISPLAY INVISIBLE (4325 3050);
FORCEPROP 2 LAST PATH I73
J 0
(4625 3225);
DISPLAY 1.021277 (4625 3225);
DISPLAY INVISIBLE (4625 3225);
FORCEPROP 2 LAST CDS_LIB standard
J 0
(4450 3150);
PAINT MONO (4450 3150);
DISPLAY INVISIBLE (4450 3150);
FORCEADD OFFPAGE..2
(4450 3050);
FORCEPROP 2 LAST $XR1 205 
J 0
(4759 3050);
DISPLAY 0.638298 (4759 3050);
PAINT MONO (4759 3050);
FORCEPROP 2 LAST $XR0 204 
J 0
(4639 3050);
DISPLAY 0.638298 (4639 3050);
PAINT MONO (4639 3050);
FORCEPROP 1 LAST COMMENT_BODY TRUE
J 0
(4405 2955);
DISPLAY 0.872340 (4405 2955);
PAINT GREEN (4405 2955);
DISPLAY INVISIBLE (4405 2955);
FORCEPROP 1 LAST OFFPAGE TRUE
J 0
(4775 2925);
DISPLAY 0.872340 (4775 2925);
PAINT GREEN (4775 2925);
DISPLAY INVISIBLE (4775 2925);
FORCEPROP 2 LAST PATH I74
J 0
(4625 3125);
DISPLAY 1.021277 (4625 3125);
DISPLAY INVISIBLE (4625 3125);
FORCEPROP 2 LAST CDS_LIB standard
J 0
(4450 3050);
PAINT MONO (4450 3050);
DISPLAY INVISIBLE (4450 3050);
FORCEADD OFFPAGE..1
R 2
(4450 2950);
FORCEPROP 2 LAST $XR0 201 
J 0
(4636 2950);
DISPLAY 0.638298 (4636 2950);
PAINT MONO (4636 2950);
FORCEPROP 2 LAST PATH I75
J 0
(4625 3025);
DISPLAY 1.021277 (4625 3025);
DISPLAY INVISIBLE (4625 3025);
FORCEPROP 1 LAST OFFPAGE TRUE
J 2
(4125 2825);
DISPLAY 0.872340 (4125 2825);
DISPLAY INVISIBLE (4125 2825);
FORCEPROP 1 LAST COMMENT_BODY TRUE
J 2
(4325 2850);
DISPLAY 0.872340 (4325 2850);
PAINT GREEN (4325 2850);
DISPLAY INVISIBLE (4325 2850);
FORCEPROP 2 LAST CDS_LIB standard
J 0
(4450 2950);
PAINT MONO (4450 2950);
DISPLAY INVISIBLE (4450 2950);
FORCEADD OFFPAGE..1
R 2
(4450 2900);
FORCEPROP 2 LAST $XR0 205 
J 0
(4636 2900);
DISPLAY 0.638298 (4636 2900);
PAINT MONO (4636 2900);
FORCEPROP 2 LAST PATH I76
J 0
(4625 2975);
DISPLAY 1.021277 (4625 2975);
DISPLAY INVISIBLE (4625 2975);
FORCEPROP 1 LAST OFFPAGE TRUE
J 2
(4125 2775);
DISPLAY 0.872340 (4125 2775);
DISPLAY INVISIBLE (4125 2775);
FORCEPROP 1 LAST COMMENT_BODY TRUE
J 2
(4325 2800);
DISPLAY 0.872340 (4325 2800);
PAINT GREEN (4325 2800);
DISPLAY INVISIBLE (4325 2800);
FORCEPROP 2 LAST CDS_LIB standard
J 0
(4450 2900);
PAINT MONO (4450 2900);
DISPLAY INVISIBLE (4450 2900);
FORCEADD OFFPAGE..2
(4450 2850);
FORCEPROP 2 LAST $XR0 203 
J 0
(4639 2850);
DISPLAY 0.638298 (4639 2850);
PAINT MONO (4639 2850);
FORCEPROP 2 LAST PATH I77
J 0
(4625 2925);
DISPLAY 1.021277 (4625 2925);
DISPLAY INVISIBLE (4625 2925);
FORCEPROP 1 LAST OFFPAGE TRUE
J 0
(4775 2725);
DISPLAY 0.872340 (4775 2725);
PAINT GREEN (4775 2725);
DISPLAY INVISIBLE (4775 2725);
FORCEPROP 1 LAST COMMENT_BODY TRUE
J 0
(4405 2755);
DISPLAY 0.872340 (4405 2755);
PAINT GREEN (4405 2755);
DISPLAY INVISIBLE (4405 2755);
FORCEPROP 2 LAST CDS_LIB standard
J 0
(4450 2850);
PAINT MONO (4450 2850);
DISPLAY INVISIBLE (4450 2850);
FORCEADD OFFPAGE..1
R 2
(4450 2800);
FORCEPROP 2 LAST $XR1 215 
J 0
(4756 2800);
DISPLAY 0.638298 (4756 2800);
PAINT MONO (4756 2800);
FORCEPROP 2 LAST $XR0 198 
J 0
(4636 2800);
DISPLAY 0.638298 (4636 2800);
PAINT MONO (4636 2800);
FORCEPROP 2 LAST CDS_LIB standard
J 0
(4450 2800);
PAINT MONO (4450 2800);
DISPLAY INVISIBLE (4450 2800);
FORCEPROP 1 LAST COMMENT_BODY TRUE
J 2
(4325 2700);
DISPLAY 0.872340 (4325 2700);
PAINT GREEN (4325 2700);
DISPLAY INVISIBLE (4325 2700);
FORCEPROP 1 LAST OFFPAGE TRUE
J 2
(4125 2675);
DISPLAY 0.872340 (4125 2675);
DISPLAY INVISIBLE (4125 2675);
FORCEPROP 2 LAST PATH I78
J 0
(4625 2875);
DISPLAY 1.021277 (4625 2875);
DISPLAY INVISIBLE (4625 2875);
FORCEADD OFFPAGE..1
R 2
(4450 2750);
FORCEPROP 2 LAST $XR0 204 
J 0
(4636 2750);
DISPLAY 0.638298 (4636 2750);
PAINT MONO (4636 2750);
FORCEPROP 1 LAST OFFPAGE TRUE
J 2
(4125 2625);
DISPLAY 0.872340 (4125 2625);
DISPLAY INVISIBLE (4125 2625);
FORCEPROP 1 LAST COMMENT_BODY TRUE
J 2
(4325 2650);
DISPLAY 0.872340 (4325 2650);
PAINT GREEN (4325 2650);
DISPLAY INVISIBLE (4325 2650);
FORCEPROP 2 LAST CDS_LIB standard
J 0
(4450 2750);
PAINT MONO (4450 2750);
DISPLAY INVISIBLE (4450 2750);
FORCEPROP 2 LAST PATH I79
J 0
(4625 2825);
DISPLAY 1.021277 (4625 2825);
DISPLAY INVISIBLE (4625 2825);
FORCEADD OFFPAGE..1
R 2
(4450 2700);
FORCEPROP 2 LAST $XR0 205 
J 0
(4636 2700);
DISPLAY 0.638298 (4636 2700);
PAINT MONO (4636 2700);
FORCEPROP 1 LAST OFFPAGE TRUE
J 2
(4125 2575);
DISPLAY 0.872340 (4125 2575);
DISPLAY INVISIBLE (4125 2575);
FORCEPROP 1 LAST COMMENT_BODY TRUE
J 2
(4325 2600);
DISPLAY 0.872340 (4325 2600);
PAINT GREEN (4325 2600);
DISPLAY INVISIBLE (4325 2600);
FORCEPROP 2 LAST CDS_LIB standard
J 0
(4450 2700);
PAINT MONO (4450 2700);
DISPLAY INVISIBLE (4450 2700);
FORCEPROP 2 LAST PATH I80
J 0
(4625 2775);
DISPLAY 1.021277 (4625 2775);
DISPLAY INVISIBLE (4625 2775);
FORCEADD OFFPAGE..2
(4450 2650);
FORCEPROP 2 LAST $XR1 215 
J 0
(4759 2650);
DISPLAY 0.638298 (4759 2650);
PAINT MONO (4759 2650);
FORCEPROP 2 LAST $XR0 201 
J 0
(4639 2650);
DISPLAY 0.638298 (4639 2650);
PAINT MONO (4639 2650);
FORCEPROP 2 LAST CDS_LIB standard
J 0
(4450 2650);
PAINT MONO (4450 2650);
DISPLAY INVISIBLE (4450 2650);
FORCEPROP 2 LAST PATH I81
J 0
(4625 2725);
DISPLAY 1.021277 (4625 2725);
DISPLAY INVISIBLE (4625 2725);
FORCEPROP 1 LAST COMMENT_BODY TRUE
J 0
(4405 2555);
DISPLAY 0.872340 (4405 2555);
PAINT GREEN (4405 2555);
DISPLAY INVISIBLE (4405 2555);
FORCEPROP 1 LAST OFFPAGE TRUE
J 0
(4775 2525);
DISPLAY 0.872340 (4775 2525);
PAINT GREEN (4775 2525);
DISPLAY INVISIBLE (4775 2525);
FORCEADD OFFPAGE..2
(4450 2550);
FORCEPROP 2 LAST $XR1 255 
J 0
(4759 2550);
DISPLAY 0.638298 (4759 2550);
PAINT MONO (4759 2550);
FORCEPROP 2 LAST $XR0 223 
J 0
(4639 2550);
DISPLAY 0.638298 (4639 2550);
PAINT MONO (4639 2550);
FORCEPROP 2 LAST CDS_LIB standard
J 0
(4450 2550);
PAINT MONO (4450 2550);
DISPLAY INVISIBLE (4450 2550);
FORCEPROP 1 LAST COMMENT_BODY TRUE
J 0
(4405 2455);
DISPLAY 0.872340 (4405 2455);
PAINT GREEN (4405 2455);
DISPLAY INVISIBLE (4405 2455);
FORCEPROP 1 LAST OFFPAGE TRUE
J 0
(4775 2425);
DISPLAY 0.872340 (4775 2425);
PAINT GREEN (4775 2425);
DISPLAY INVISIBLE (4775 2425);
FORCEPROP 2 LAST PATH I83
J 0
(4625 2625);
DISPLAY 1.021277 (4625 2625);
DISPLAY INVISIBLE (4625 2625);
FORCEADD OFFPAGE..3
(4450 2200);
FORCEPROP 2 LAST $XR0 241 
J 0
(4664 2200);
DISPLAY 0.638298 (4664 2200);
PAINT MONO (4664 2200);
FORCEPROP 2 LAST CDS_LIB standard
J 0
(4450 2200);
PAINT MONO (4450 2200);
DISPLAY INVISIBLE (4450 2200);
FORCEPROP 2 LAST PATH I85
J 0
(4650 2275);
DISPLAY 1.021277 (4650 2275);
DISPLAY INVISIBLE (4650 2275);
FORCEPROP 1 LAST COMMENT_BODY TRUE
J 0
(4400 2100);
DISPLAY 0.872340 (4400 2100);
PAINT GREEN (4400 2100);
DISPLAY INVISIBLE (4400 2100);
FORCEPROP 1 LAST OFFPAGE TRUE
J 0
(4775 2075);
DISPLAY 0.872340 (4775 2075);
PAINT GREEN (4775 2075);
DISPLAY INVISIBLE (4775 2075);
FORCEADD OFFPAGE..1
R 2
(4450 2300);
FORCEPROP 2 LAST $XR1 201 
J 0
(4756 2300);
DISPLAY 0.638298 (4756 2300);
PAINT MONO (4756 2300);
FORCEPROP 2 LAST $XR0 198 
J 0
(4636 2300);
DISPLAY 0.638298 (4636 2300);
PAINT MONO (4636 2300);
FORCEPROP 2 LAST CDS_LIB standard
J 0
(4450 2300);
PAINT MONO (4450 2300);
DISPLAY INVISIBLE (4450 2300);
FORCEPROP 2 LAST PATH I86
J 0
(4625 2375);
DISPLAY 1.021277 (4625 2375);
DISPLAY INVISIBLE (4625 2375);
FORCEPROP 1 LAST COMMENT_BODY TRUE
J 2
(4325 2200);
DISPLAY 0.872340 (4325 2200);
PAINT GREEN (4325 2200);
DISPLAY INVISIBLE (4325 2200);
FORCEPROP 1 LAST OFFPAGE TRUE
J 2
(4125 2175);
DISPLAY 0.872340 (4125 2175);
DISPLAY INVISIBLE (4125 2175);
FORCEADD OFFPAGE..1
R 2
(4450 2350);
FORCEPROP 2 LAST $XR0 199 
J 0
(4636 2350);
DISPLAY 0.638298 (4636 2350);
PAINT MONO (4636 2350);
FORCEPROP 2 LAST CDS_LIB standard
J 0
(4450 2350);
PAINT MONO (4450 2350);
DISPLAY INVISIBLE (4450 2350);
FORCEPROP 1 LAST COMMENT_BODY TRUE
J 2
(4325 2250);
DISPLAY 0.872340 (4325 2250);
PAINT GREEN (4325 2250);
DISPLAY INVISIBLE (4325 2250);
FORCEPROP 1 LAST OFFPAGE TRUE
J 2
(4125 2225);
DISPLAY 0.872340 (4125 2225);
DISPLAY INVISIBLE (4125 2225);
FORCEPROP 2 LAST PATH I87
J 0
(4625 2425);
DISPLAY 1.021277 (4625 2425);
DISPLAY INVISIBLE (4625 2425);
FORCEADD OFFPAGE..1
R 2
(4450 2400);
FORCEPROP 2 LAST $XR0 183 
J 0
(4636 2400);
DISPLAY 0.638298 (4636 2400);
PAINT MONO (4636 2400);
FORCEPROP 2 LAST CDS_LIB standard
J 0
(4450 2400);
PAINT MONO (4450 2400);
DISPLAY INVISIBLE (4450 2400);
FORCEPROP 1 LAST COMMENT_BODY TRUE
J 2
(4325 2300);
DISPLAY 0.872340 (4325 2300);
PAINT GREEN (4325 2300);
DISPLAY INVISIBLE (4325 2300);
FORCEPROP 1 LAST OFFPAGE TRUE
J 2
(4125 2275);
DISPLAY 0.872340 (4125 2275);
DISPLAY INVISIBLE (4125 2275);
FORCEPROP 2 LAST PATH I88
J 0
(4625 2475);
DISPLAY 1.021277 (4625 2475);
DISPLAY INVISIBLE (4625 2475);
FORCEADD OFFPAGE..1
R 2
(4450 2450);
FORCEPROP 2 LAST $XR0 204 
J 0
(4636 2450);
DISPLAY 0.638298 (4636 2450);
PAINT MONO (4636 2450);
FORCEPROP 2 LAST PATH I89
J 0
(4625 2525);
DISPLAY 1.021277 (4625 2525);
DISPLAY INVISIBLE (4625 2525);
FORCEPROP 1 LAST OFFPAGE TRUE
J 2
(4125 2325);
DISPLAY 0.872340 (4125 2325);
DISPLAY INVISIBLE (4125 2325);
FORCEPROP 1 LAST COMMENT_BODY TRUE
J 2
(4325 2350);
DISPLAY 0.872340 (4325 2350);
PAINT GREEN (4325 2350);
DISPLAY INVISIBLE (4325 2350);
FORCEPROP 2 LAST CDS_LIB standard
J 0
(4450 2450);
PAINT MONO (4450 2450);
DISPLAY INVISIBLE (4450 2450);
FORCEADD OFFPAGE..1
R 2
(4450 2500);
FORCEPROP 2 LAST $XR1 215 
J 0
(4756 2500);
DISPLAY 0.638298 (4756 2500);
PAINT MONO (4756 2500);
FORCEPROP 2 LAST $XR0 204 
J 0
(4636 2500);
DISPLAY 0.638298 (4636 2500);
PAINT MONO (4636 2500);
FORCEPROP 2 LAST PATH I90
J 0
(4625 2575);
DISPLAY 1.021277 (4625 2575);
DISPLAY INVISIBLE (4625 2575);
FORCEPROP 2 LAST CDS_LIB standard
J 0
(4450 2500);
PAINT MONO (4450 2500);
DISPLAY INVISIBLE (4450 2500);
FORCEPROP 1 LAST COMMENT_BODY TRUE
J 2
(4325 2400);
DISPLAY 0.872340 (4325 2400);
PAINT GREEN (4325 2400);
DISPLAY INVISIBLE (4325 2400);
FORCEPROP 1 LAST OFFPAGE TRUE
J 2
(4125 2375);
DISPLAY 0.872340 (4125 2375);
DISPLAY INVISIBLE (4125 2375);
FORCEADD OFFPAGE..1
(-1925 3400);
FORCEPROP 2 LAST $XR0 204 
J 0
(-2207 3400);
DISPLAY 0.638298 (-2207 3400);
PAINT MONO (-2207 3400);
FORCEPROP 2 LAST PATH I91
J 0
(-1875 3475);
DISPLAY 1.021277 (-1875 3475);
DISPLAY INVISIBLE (-1875 3475);
FORCEPROP 2 LAST CDS_LIB standard
J 0
(-1925 3400);
PAINT MONO (-1925 3400);
DISPLAY INVISIBLE (-1925 3400);
FORCEPROP 1 LAST OFFPAGE TRUE
J 0
(-1600 3275);
DISPLAY 0.872340 (-1600 3275);
DISPLAY INVISIBLE (-1600 3275);
FORCEPROP 1 LAST COMMENT_BODY TRUE
J 0
(-1800 3300);
DISPLAY 1.170213 (-1800 3300);
PAINT GREEN (-1800 3300);
DISPLAY INVISIBLE (-1800 3300);
FORCEADD OFFPAGE..1
(-1925 3350);
FORCEPROP 2 LAST $XR1 204 
J 0
(-2327 3350);
DISPLAY 0.638298 (-2327 3350);
PAINT MONO (-2327 3350);
FORCEPROP 2 LAST $XR0 202 
J 0
(-2207 3350);
DISPLAY 0.638298 (-2207 3350);
PAINT MONO (-2207 3350);
FORCEPROP 2 LAST PATH I92
J 0
(-1875 3425);
DISPLAY 1.021277 (-1875 3425);
DISPLAY INVISIBLE (-1875 3425);
FORCEPROP 1 LAST COMMENT_BODY TRUE
J 0
(-1800 3250);
DISPLAY 1.170213 (-1800 3250);
PAINT GREEN (-1800 3250);
DISPLAY INVISIBLE (-1800 3250);
FORCEPROP 1 LAST OFFPAGE TRUE
J 0
(-1600 3225);
DISPLAY 0.872340 (-1600 3225);
DISPLAY INVISIBLE (-1600 3225);
FORCEPROP 2 LAST CDS_LIB standard
J 0
(-1925 3350);
PAINT MONO (-1925 3350);
DISPLAY INVISIBLE (-1925 3350);
FORCEADD EMMITSBURG_REV0P9..5
(1325 3200);
FORCEPROP 1 LAST PART_NUMBER AJ0QV2N0T00
J 0
(-400 4525);
DISPLAY 0.723404 (-400 4525);
PAINT GREEN (-400 4525);
DISPLAY INVISIBLE (-400 4525);
FORCEPROP 2 LAST VALUE GFNOCPU04302300-QV2N-MM#99A1WT
J 0
(-400 4675);
DISPLAY 1.021277 (-400 4675);
FORCEPROP 2 LAST PART_TYPE SMLF
J 0
(-400 4725);
DISPLAY 1.021277 (-400 4725);
FORCEPROP 1 LAST MATERIAL IC
J 0
(-396 4465);
DISPLAY 0.723404 (-396 4465);
PAINT GREEN (-396 4465);
FORCEPROP 1 LAST $LOCATION U4
J 0
(-400 4600);
DISPLAY 0.723404 (-400 4600);
PAINT GREEN (-400 4600);
FORCEPROP 2 LASTPIN (3200 2150) $PN AF2
J 0
(3210 2160);
DISPLAY 0.808511 (3210 2160);
FORCEPROP 2 LASTPIN (3200 2200) $PN AE1
J 0
(3210 2210);
DISPLAY 0.808511 (3210 2210);
FORCEPROP 2 LASTPIN (3200 2250) $PN AD2
J 0
(3210 2260);
DISPLAY 0.808511 (3210 2260);
FORCEPROP 2 LASTPIN (3200 2300) $PN AJ1
J 0
(3210 2310);
DISPLAY 0.808511 (3210 2310);
FORCEPROP 2 LASTPIN (3200 2350) $PN AG1
J 0
(3210 2360);
DISPLAY 0.808511 (3210 2360);
FORCEPROP 2 LASTPIN (3200 2400) $PN AE3
J 0
(3210 2410);
DISPLAY 0.808511 (3210 2410);
FORCEPROP 2 LASTPIN (3200 2450) $PN AJ3
J 0
(3210 2460);
DISPLAY 0.808511 (3210 2460);
FORCEPROP 2 LASTPIN (3200 2500) $PN AB2
J 0
(3210 2510);
DISPLAY 0.808511 (3210 2510);
FORCEPROP 2 LASTPIN (3200 2550) $PN AB4
J 0
(3210 2560);
DISPLAY 0.808511 (3210 2560);
FORCEPROP 2 LASTPIN (3200 2600) $PN AH2
J 0
(3210 2610);
DISPLAY 0.808511 (3210 2610);
FORCEPROP 2 LASTPIN (3200 2650) $PN AC1
J 0
(3210 2660);
DISPLAY 0.808511 (3210 2660);
FORCEPROP 2 LASTPIN (3200 2700) $PN AH4
J 0
(3210 2710);
DISPLAY 0.808511 (3210 2710);
FORCEPROP 2 LASTPIN (3200 2750) $PN AC3
J 0
(3210 2760);
DISPLAY 0.808511 (3210 2760);
FORCEPROP 2 LASTPIN (3200 2800) $PN AD4
J 0
(3210 2810);
DISPLAY 0.808511 (3210 2810);
FORCEPROP 2 LASTPIN (3200 2850) $PN Y2
J 0
(3210 2860);
DISPLAY 0.808511 (3210 2860);
FORCEPROP 2 LASTPIN (3200 2900) $PN AF4
J 0
(3210 2910);
DISPLAY 0.808511 (3210 2910);
FORCEPROP 2 LASTPIN (3200 2950) $PN Y4
J 0
(3210 2960);
DISPLAY 0.808511 (3210 2960);
FORCEPROP 2 LASTPIN (3200 3000) $PN AG3
J 0
(3210 3010);
DISPLAY 0.808511 (3210 3010);
FORCEPROP 2 LASTPIN (3200 3050) $PN AA1
J 0
(3210 3060);
DISPLAY 0.808511 (3210 3060);
FORCEPROP 2 LASTPIN (3200 3100) $PN AA3
J 0
(3210 3110);
DISPLAY 0.808511 (3210 3110);
FORCEPROP 2 LASTPIN (3200 3150) $PN W1
J 0
(3210 3160);
DISPLAY 0.808511 (3210 3160);
FORCEPROP 2 LASTPIN (-550 3350) $PN BG20
J 2
(-560 3360);
DISPLAY 0.808511 (-560 3360);
FORCEPROP 2 LASTPIN (-550 3400) $PN BD15
J 2
(-560 3410);
DISPLAY 0.808511 (-560 3410);
FORCEPROP 2 LASTPIN (-550 3450) $PN BG12
J 2
(-560 3460);
DISPLAY 0.808511 (-560 3460);
FORCEPROP 2 LASTPIN (-550 3500) $PN BF19
J 2
(-560 3510);
DISPLAY 0.808511 (-560 3510);
FORCEPROP 2 LASTPIN (-550 3550) $PN BE18
J 2
(-560 3560);
DISPLAY 0.808511 (-560 3560);
FORCEPROP 2 LASTPIN (-550 3600) $PN BD19
J 2
(-560 3610);
DISPLAY 0.808511 (-560 3610);
FORCEPROP 2 LASTPIN (-550 3650) $PN BE20
J 2
(-560 3660);
DISPLAY 0.808511 (-560 3660);
FORCEPROP 2 LASTPIN (-550 3700) $PN BE16
J 2
(-560 3710);
DISPLAY 0.808511 (-560 3710);
FORCEPROP 2 LASTPIN (-550 3750) $PN BF17
J 2
(-560 3760);
DISPLAY 0.808511 (-560 3760);
FORCEPROP 2 LASTPIN (-550 3800) $PN BD13
J 2
(-560 3810);
DISPLAY 0.808511 (-560 3810);
FORCEPROP 2 LASTPIN (-550 3850) $PN BD17
J 2
(-560 3860);
DISPLAY 0.808511 (-560 3860);
FORCEPROP 2 LASTPIN (-550 3900) $PN BG18
J 2
(-560 3910);
DISPLAY 0.808511 (-560 3910);
FORCEPROP 2 LASTPIN (-550 3950) $PN BG16
J 2
(-560 3960);
DISPLAY 0.808511 (-560 3960);
FORCEPROP 2 LASTPIN (-550 4000) $PN BF15
J 2
(-560 4010);
DISPLAY 0.808511 (-560 4010);
FORCEPROP 2 LASTPIN (-550 4050) $PN BE12
J 2
(-560 4060);
DISPLAY 0.808511 (-560 4060);
FORCEPROP 2 LASTPIN (-550 4100) $PN BE14
J 2
(-560 4110);
DISPLAY 0.808511 (-560 4110);
FORCEPROP 2 LASTPIN (-550 4150) $PN BD11
J 2
(-560 4160);
DISPLAY 0.808511 (-560 4160);
FORCEPROP 2 LASTPIN (-550 4200) $PN BF13
J 2
(-560 4210);
DISPLAY 0.808511 (-560 4210);
FORCEPROP 2 LASTPIN (-550 4250) $PN BF11
J 2
(-560 4260);
DISPLAY 0.808511 (-560 4260);
FORCEPROP 2 LASTPIN (-550 4300) $PN BG14
J 2
(-560 4310);
DISPLAY 0.808511 (-560 4310);
FORCEPROP 2 LASTPIN (-550 2100) $PN BD33
J 2
(-560 2110);
DISPLAY 0.808511 (-560 2110);
FORCEPROP 2 LASTPIN (-550 2150) $PN BE32
J 2
(-560 2160);
DISPLAY 0.808511 (-560 2160);
FORCEPROP 2 LASTPIN (-550 2200) $PN BF33
J 2
(-560 2210);
DISPLAY 0.808511 (-560 2210);
FORCEPROP 2 LASTPIN (-550 2250) $PN BD31
J 2
(-560 2260);
DISPLAY 0.808511 (-560 2260);
FORCEPROP 2 LASTPIN (-550 2300) $PN BE30
J 2
(-560 2310);
DISPLAY 0.808511 (-560 2310);
FORCEPROP 2 LASTPIN (-550 2350) $PN BF31
J 2
(-560 2360);
DISPLAY 0.808511 (-560 2360);
FORCEPROP 2 LASTPIN (-550 2400) $PN BG32
J 2
(-560 2410);
DISPLAY 0.808511 (-560 2410);
FORCEPROP 2 LASTPIN (-550 2450) $PN BG30
J 2
(-560 2460);
DISPLAY 0.808511 (-560 2460);
FORCEPROP 2 LASTPIN (-550 2500) $PN BG28
J 2
(-560 2510);
DISPLAY 0.808511 (-560 2510);
FORCEPROP 2 LASTPIN (-550 2550) $PN BG26
J 2
(-560 2560);
DISPLAY 0.808511 (-560 2560);
FORCEPROP 2 LASTPIN (-550 2600) $PN BG24
J 2
(-560 2610);
DISPLAY 0.808511 (-560 2610);
FORCEPROP 2 LASTPIN (-550 2650) $PN BG22
J 2
(-560 2660);
DISPLAY 0.808511 (-560 2660);
FORCEPROP 2 LASTPIN (-550 2700) $PN BD29
J 2
(-560 2710);
DISPLAY 0.808511 (-560 2710);
FORCEPROP 2 LASTPIN (-550 2750) $PN BE28
J 2
(-560 2760);
DISPLAY 0.808511 (-560 2760);
FORCEPROP 2 LASTPIN (-550 2800) $PN BF29
J 2
(-560 2810);
DISPLAY 0.808511 (-560 2810);
FORCEPROP 2 LASTPIN (-550 2850) $PN BD27
J 2
(-560 2860);
DISPLAY 0.808511 (-560 2860);
FORCEPROP 2 LASTPIN (-550 2900) $PN BE26
J 2
(-560 2910);
DISPLAY 0.808511 (-560 2910);
FORCEPROP 2 LASTPIN (-550 2950) $PN BF27
J 2
(-560 2960);
DISPLAY 0.808511 (-560 2960);
FORCEPROP 2 LASTPIN (-550 3000) $PN BD25
J 2
(-560 3010);
DISPLAY 0.808511 (-560 3010);
FORCEPROP 2 LASTPIN (-550 3050) $PN BF25
J 2
(-560 3060);
DISPLAY 0.808511 (-560 3060);
FORCEPROP 2 LASTPIN (-550 3100) $PN BE24
J 2
(-560 3110);
DISPLAY 0.808511 (-560 3110);
FORCEPROP 2 LASTPIN (-550 3150) $PN BF23
J 2
(-560 3160);
DISPLAY 0.808511 (-560 3160);
FORCEPROP 2 LASTPIN (-550 3200) $PN BE22
J 2
(-560 3210);
DISPLAY 0.808511 (-560 3210);
FORCEPROP 2 LASTPIN (-550 3250) $PN BD23
J 2
(-560 3260);
DISPLAY 0.808511 (-560 3260);
FORCEPROP 2 LASTPIN (3200 3250) $PN BC4
J 0
(3210 3260);
DISPLAY 0.808511 (3210 3260);
FORCEPROP 2 LASTPIN (3200 3300) $PN BA4
J 0
(3210 3310);
DISPLAY 0.808511 (3210 3310);
FORCEPROP 2 LASTPIN (3200 3350) $PN AU2
J 0
(3210 3360);
DISPLAY 0.808511 (3210 3360);
FORCEPROP 2 LASTPIN (3200 3400) $PN AU4
J 0
(3210 3410);
DISPLAY 0.808511 (3210 3410);
FORCEPROP 2 LASTPIN (3200 3450) $PN BB3
J 0
(3210 3460);
DISPLAY 0.808511 (3210 3460);
FORCEPROP 2 LASTPIN (3200 3500) $PN AT3
J 0
(3210 3510);
DISPLAY 0.808511 (3210 3510);
FORCEPROP 2 LASTPIN (3200 3550) $PN AP1
J 0
(3210 3560);
DISPLAY 0.808511 (3210 3560);
FORCEPROP 2 LASTPIN (3200 3600) $PN AW4
J 0
(3210 3610);
DISPLAY 0.808511 (3210 3610);
FORCEPROP 2 LASTPIN (3200 3650) $PN AR4
J 0
(3210 3660);
DISPLAY 0.808511 (3210 3660);
FORCEPROP 2 LASTPIN (3200 3700) $PN AR2
J 0
(3210 3710);
DISPLAY 0.808511 (3210 3710);
FORCEPROP 2 LASTPIN (3200 3750) $PN AP3
J 0
(3210 3760);
DISPLAY 0.808511 (3210 3760);
FORCEPROP 2 LASTPIN (3200 3800) $PN AV3
J 0
(3210 3810);
DISPLAY 0.808511 (3210 3810);
FORCEPROP 2 LASTPIN (3200 3850) $PN AN4
J 0
(3210 3860);
DISPLAY 0.808511 (3210 3860);
FORCEPROP 2 LASTPIN (3200 3900) $PN AY1
J 0
(3210 3910);
DISPLAY 0.808511 (3210 3910);
FORCEPROP 2 LASTPIN (3200 3950) $PN AW2
J 0
(3210 3960);
DISPLAY 0.808511 (3210 3960);
FORCEPROP 2 LASTPIN (3200 4000) $PN BA2
J 0
(3210 4010);
DISPLAY 0.808511 (3210 4010);
FORCEPROP 2 LASTPIN (3200 4050) $PN AV1
J 0
(3210 4060);
DISPLAY 0.808511 (3210 4060);
FORCEPROP 2 LASTPIN (3200 4100) $PN AL3
J 0
(3210 4110);
DISPLAY 0.808511 (3210 4110);
FORCEPROP 2 LASTPIN (3200 4150) $PN AL5
J 0
(3210 4160);
DISPLAY 0.808511 (3210 4160);
FORCEPROP 2 LASTPIN (3200 4200) $PN AL1
J 0
(3210 4210);
DISPLAY 0.808511 (3210 4210);
FORCEPROP 2 LASTPIN (3200 4250) $PN AT1
J 0
(3210 4260);
DISPLAY 0.808511 (3210 4260);
FORCEPROP 2 LASTPIN (3200 4300) $PN AN2
J 0
(3210 4310);
DISPLAY 0.808511 (3210 4310);
FORCEPROP 1 LAST NEEDS_NO_SIZE TRUE
J 0
(1325 3200);
DISPLAY 0.723404 (1325 3200);
PAINT GREEN (1325 3200);
DISPLAY INVISIBLE (1325 3200);
FORCEPROP 1 LAST CDS_LMAN_SYM_OUTLINE -1725,1250,1725,-1250
J 0
(1325 3200);
DISPLAY 0.468085 (1325 3200);
PAINT GREEN (1325 3200);
DISPLAY INVISIBLE (1325 3200);
FORCEPROP 2 LAST CDS_LIB pure_quanta
J 0
(1325 3200);
PAINT MONO (1325 3200);
DISPLAY INVISIBLE (1325 3200);
FORCEPROP 1 LAST PATH I93
J 0
(1325 3200);
DISPLAY 0.723404 (1325 3200);
PAINT GREEN (1325 3200);
DISPLAY INVISIBLE (1325 3200);
FORCEPROP 2 LAST CDS_LOCATION U4
J 0
(-375 4600);
DISPLAY 1.021277 (-375 4600);
DISPLAY INVISIBLE (-375 4600);
FORCEPROP 2 LAST $SEC 5
J 0
(-375 4800);
DISPLAY 0.680851 (-375 4800);
PAINT MONO (-375 4800);
DISPLAY INVISIBLE (-375 4800);
FORCEPROP 2 LAST CDS_SEC 5
J 0
(-375 4600);
DISPLAY 1.021277 (-375 4600);
DISPLAY INVISIBLE (-375 4600);
FORCEADD OFFPAGE..2
(4500 900);
FORCEPROP 2 LAST $XR0 183 
J 0
(4689 900);
DISPLAY 0.638298 (4689 900);
PAINT MONO (4689 900);
FORCEPROP 2 LAST PATH I99
J 0
(4850 950);
DISPLAY 1.021277 (4850 950);
DISPLAY INVISIBLE (4850 950);
FORCEPROP 2 LAST CDS_LIB standard
J 0
(4500 900);
DISPLAY INVISIBLE (4500 900);
FORCEPROP 1 LAST OFFPAGE TRUE
J 0
(4825 775);
DISPLAY 0.872340 (4825 775);
DISPLAY INVISIBLE (4825 775);
FORCEPROP 1 LAST COMMENT_BODY TRUE
J 0
(4455 805);
DISPLAY 0.872340 (4455 805);
PAINT GREEN (4455 805);
DISPLAY INVISIBLE (4455 805);
FORCEADD DESIGN_NOTE..1
(-1975 4650);
FORCEPROP 0 LAST L1 GPPC_A_[10-19]: POWER RAIL --> 3.3V
J 0
(-2175 4525);
DISPLAY 0.851064 (-2175 4525);
PAINT SKYBLUE (-2175 4525);
FORCEPROP 2 LAST CDS_LIB logical_power
J 0
(-1975 4650);
DISPLAY INVISIBLE (-1975 4650);
FORCEPROP 1 LAST COMMENT_BODY TRUE
J 0
(-1950 4750);
DISPLAY 0.978723 (-1950 4750);
DISPLAY INVISIBLE (-1950 4750);
FORCEADD DNS..3
(-3125 1500);
PAINT RED (-3125 1500);
FORCEPROP 2 LAST CDS_LIB mstr_misc
J 0
(-3125 1500);
DISPLAY INVISIBLE (-3125 1500);
FORCEPROP 1 LAST COMMENT_BODY TRUE
R 1
J 0
(-3050 1275);
DISPLAY 0.872340 (-3050 1275);
PAINT GREEN (-3050 1275);
DISPLAY INVISIBLE (-3050 1275);
FORCEADD DNS..3
(-3125 925);
PAINT RED (-3125 925);
FORCEPROP 2 LAST CDS_LIB mstr_misc
J 0
(-3125 925);
DISPLAY INVISIBLE (-3125 925);
FORCEPROP 1 LAST COMMENT_BODY TRUE
R 1
J 0
(-3050 700);
DISPLAY 0.872340 (-3050 700);
PAINT GREEN (-3050 700);
DISPLAY INVISIBLE (-3050 700);
FORCEADD DNS..2
(-2675 4000);
PAINT RED (-2675 4000);
FORCEPROP 1 LAST COMMENT_BODY TRUE
J 0
(-2675 4000);
DISPLAY INVISIBLE (-2675 4000);
FORCEPROP 2 LAST CDS_LIB mstr_misc
J 0
(-2675 4000);
DISPLAY INVISIBLE (-2675 4000);
FORCEADD DNS..2
(-2675 3900);
PAINT RED (-2675 3900);
FORCEPROP 2 LAST CDS_LIB mstr_misc
J 0
(-2675 3900);
DISPLAY INVISIBLE (-2675 3900);
FORCEPROP 1 LAST COMMENT_BODY TRUE
J 0
(-2675 3900);
DISPLAY INVISIBLE (-2675 3900);
FORCEADD QUANTA_TITLE_BLOCK_C..1
(5450 -1725);
FORCEPROP 0 LAST CDS_CON_LAST_MODIFIED Fri Aug 25 14:02:55 2023
J 0
(3565 -1710);
PAINT MONO (3565 -1710);
DISPLAY INVISIBLE (3565 -1710);
FORCEPROP 2 LAST CUSTOM_TXT_CDS <XR_PAGE_TITLE>
J 0
(-2440 3525);
DISPLAY 0.638298 (-2440 3525);
PAINT PINK (-2440 3525);
DISPLAY INVISIBLE (-2440 3525);
FORCEPROP 2 LAST CUSTOM_TXT_CDS <NAME_1>
J 0
(2275 -1550);
FORCEPROP 2 LAST CUSTOM_TXT_CDS <Q_PROJ>
J 0
(3068 -1623);
DISPLAY 1.212766 (3068 -1623);
FORCEPROP 2 LAST CUSTOM_TXT_CDS <CON_LAST_MODIFIED>
J 0
(3565 -1710);
DISPLAY 0.978723 (3565 -1710);
FORCEPROP 2 LAST CUSTOM_TXT_CDS <Q_REV>
J 0
(5266 -1622);
DISPLAY 1.212766 (5266 -1622);
FORCEPROP 2 LAST CUSTOM_TXT_CDS <NAME_2>
J 0
(2275 -1675);
FORCEPROP 2 LAST CUSTOM_TXT_CDS <CON_PAGE_NUM> OF <CON_TOTAL_PAGES>
J 0
(5004 -1707);
DISPLAY 0.978723 (5004 -1707);
FORCEPROP 2 LAST CUSTOM_TXT_CDS <Q_NUMBER>
J 0
(4047 -1622);
DISPLAY 1.212766 (4047 -1622);
FORCEPROP 1 LAST Q_TITLE EMMITSBURG - GPIO/SMB (5/10)
J 0
(-3866 -1699);
DISPLAY 1.957447 (-3866 -1699);
PAINT GREEN (-3866 -1699);
FORCEPROP 1 LAST Q_DEPT 
J 1
(1687 -1676);
DISPLAY 1.957447 (1687 -1676);
PAINT GREEN (1687 -1676);
FORCEPROP 2 LAST CDS_XR_PAGE_TITLE CR-183 : @S9S_MB_2U_LIB.S9S_MB_2U(SCH_1):PAGE183
J 0
(-2440 3525);
DISPLAY 0.638298 (-2440 3525);
PAINT PINK (-2440 3525);
DISPLAY INVISIBLE (-2440 3525);
FORCEPROP 2 LAST CDS_LIB pure_quanta
J 0
(5450 -1725);
PAINT MONO (5450 -1725);
DISPLAY INVISIBLE (5450 -1725);
FORCEPROP 1 LAST CDS_LMAN_SYM_OUTLINE -9475,6775,100,-125
J 0
(5450 -1725);
DISPLAY 0.468085 (5450 -1725);
PAINT GREEN (5450 -1725);
DISPLAY INVISIBLE (5450 -1725);
FORCEPROP 2 LAST PAGE_BORDER TRUE
J 0
(-2440 3525);
DISPLAY 0.638298 (-2440 3525);
PAINT PINK (-2440 3525);
DISPLAY INVISIBLE (-2440 3525);
FORCEPROP 1 LAST COMMENT_BODY TRUE
J 0
(5462 -1738);
DISPLAY 0.978723 (5462 -1738);
PAINT GREEN (5462 -1738);
DISPLAY INVISIBLE (5462 -1738);
WIRE 16 -1 (4525 50)(4525 -25);
WIRE 16 -1 (-900 -1000)(-900 -950);
WIRE 16 -1 (-650 75)(-650 25);
WIRE 16 -1 (-1000 75)(-650 75);
WIRE 16 -1 (3450 300)(3450 225);
WIRE 16 -1 (3050 300)(3450 300);
WIRE 16 -1 (-2825 1400)(-2825 1525);
WIRE 16 -1 (-2825 825)(-2825 950);
WIRE 16 -1 (-2825 950)(-2925 950);
WIRE 16 -1 (-1725 1000)(-2925 1000);
FORCEPROP 2 LAST SIG_NAME SMB_SML1_PMBUS_3V3AUX_PCH_SCL_R1
J 0
(-2710 1010);
DISPLAY 0.680851 (-2710 1010);
PAINT WHITE (-2710 1010);
WIRE 16 -1 (-1875 3000)(-550 3000);
FORCEPROP 0 LAST CDS_PHYS_NET_NAME FM_PCH_SLP_S4_N
J 0
(-1850 3042);
PAINT MONO (-1850 3042);
DISPLAY INVISIBLE (-1850 3042);
FORCEPROP 0 LAST SIG_NAME JTAG_TRC_PCH_PTI<11>
J 0
(-1775 3010);
DISPLAY 0.680851 (-1775 3010);
PAINT WHITE (-1775 3010);
WIRE 16 -1 (-1875 3100)(-550 3100);
FORCEPROP 0 LAST CDS_PHYS_NET_NAME FM_PCH_SLP_S4_N
J 0
(-1850 3142);
PAINT MONO (-1850 3142);
DISPLAY INVISIBLE (-1850 3142);
FORCEPROP 0 LAST SIG_NAME JTAG_TRC_PCH_PTI<13>
J 0
(-1775 3110);
DISPLAY 0.680851 (-1775 3110);
PAINT WHITE (-1775 3110);
WIRE 16 -1 (-1875 3150)(-550 3150);
FORCEPROP 0 LAST CDS_PHYS_NET_NAME FM_PCH_SLP_S4_N
J 0
(-1850 3192);
PAINT MONO (-1850 3192);
DISPLAY INVISIBLE (-1850 3192);
FORCEPROP 0 LAST SIG_NAME JTAG_TRC_PCH_PTI<14>
J 0
(-1775 3160);
DISPLAY 0.680851 (-1775 3160);
PAINT WHITE (-1775 3160);
WIRE 16 -1 (-1875 3200)(-550 3200);
FORCEPROP 0 LAST CDS_PHYS_NET_NAME FM_PCH_SLP_S4_N
J 0
(-1850 3242);
PAINT MONO (-1850 3242);
DISPLAY INVISIBLE (-1850 3242);
FORCEPROP 0 LAST SIG_NAME JTAG_TRC_PCH_PTI<15>
J 0
(-1775 3210);
DISPLAY 0.680851 (-1775 3210);
PAINT WHITE (-1775 3210);
WIRE 16 -1 (-1875 3250)(-550 3250);
FORCEPROP 0 LAST CDS_PHYS_NET_NAME FM_PCH_SLP_S4_N
J 0
(-1850 3292);
PAINT MONO (-1850 3292);
DISPLAY INVISIBLE (-1850 3292);
FORCEPROP 0 LAST SIG_NAME JTAG_TRC_PCH_PTI1_CLK
J 0
(-1775 3260);
DISPLAY 0.680851 (-1775 3260);
PAINT WHITE (-1775 3260);
WIRE 16 -1 (-1875 3350)(-550 3350);
FORCEPROP 0 LAST CDS_PHYS_NET_NAME FM_PCH_SLP_S4_N
J 0
(-1850 3392);
PAINT MONO (-1850 3392);
DISPLAY INVISIBLE (-1850 3392);
FORCEPROP 0 LAST SIG_NAME IRQ_LPC_PIRQA_N_ESPI_ALERT0_N
J 0
(-1775 3360);
DISPLAY 0.680851 (-1775 3360);
PAINT WHITE (-1775 3360);
WIRE 16 -1 (-1875 3600)(-550 3600);
FORCEPROP 0 LAST CDS_PHYS_NET_NAME FM_PCH_SLP_S4_N
J 0
(-1850 3642);
PAINT MONO (-1850 3642);
DISPLAY INVISIBLE (-1850 3642);
FORCEPROP 0 LAST SIG_NAME ESPI_LAD0_DATA_IO3
J 0
(-1775 3610);
DISPLAY 0.680851 (-1775 3610);
PAINT WHITE (-1775 3610);
WIRE 16 -1 (-1875 3700)(-550 3700);
FORCEPROP 0 LAST CDS_PHYS_NET_NAME FM_PCH_SLP_S4_N
J 0
(-1850 3742);
PAINT MONO (-1850 3742);
DISPLAY INVISIBLE (-1850 3742);
FORCEPROP 0 LAST SIG_NAME IRQ_LPC_SERIRQ_ESPI_CS1_N
J 0
(-1775 3710);
DISPLAY 0.680851 (-1775 3710);
PAINT WHITE (-1775 3710);
WIRE 16 -1 (-1875 4050)(-550 4050);
FORCEPROP 0 LAST CDS_PHYS_NET_NAME FM_PCH_SLP_S4_N
J 0
(-1850 4092);
PAINT MONO (-1850 4092);
DISPLAY INVISIBLE (-1850 4092);
FORCEPROP 0 LAST SIG_NAME PD_PCH_GPPC_A_14
J 0
(-1775 4060);
DISPLAY 0.680851 (-1775 4060);
PAINT WHITE (-1775 4060);
WIRE 16 -1 (-1875 4100)(-550 4100);
FORCEPROP 0 LAST CDS_PHYS_NET_NAME FM_PCH_SLP_S4_N
J 0
(-1850 4142);
PAINT MONO (-1850 4142);
DISPLAY INVISIBLE (-1850 4142);
FORCEPROP 0 LAST SIG_NAME PD_PCH_GPPC_A_15
J 0
(-1775 4110);
DISPLAY 0.680851 (-1775 4110);
PAINT WHITE (-1775 4110);
WIRE 16 -1 (-1875 4150)(-550 4150);
FORCEPROP 0 LAST CDS_PHYS_NET_NAME FM_PCH_SLP_S4_N
J 0
(-1850 4192);
PAINT MONO (-1850 4192);
DISPLAY INVISIBLE (-1850 4192);
FORCEPROP 0 LAST SIG_NAME FM_PCH_SATA_RAID_KEY
J 0
(-1775 4160);
DISPLAY 0.680851 (-1775 4160);
PAINT WHITE (-1775 4160);
WIRE 16 -1 (-1875 4000)(-550 4000);
FORCEPROP 0 LAST CDS_PHYS_NET_NAME TP_PCH_GPPC_A_14
J 0
(-1850 4042);
PAINT MONO (-1850 4042);
DISPLAY INVISIBLE (-1850 4042);
FORCEPROP 0 LAST SIG_NAME FM_BMC_READY_R_N
J 0
(-1775 4010);
DISPLAY 0.680851 (-1775 4010);
PAINT WHITE (-1775 4010);
WIRE 16 -1 (-2600 4000)(-2525 4000);
FORCEPROP 2 LAST SIG_NAME E1S_0_CLKREQ_N
J 0
(-1785 3910);
DISPLAY 0.638298 (-1785 3910);
PAINT WHITE (-1785 3910);
WIRE 16 -1 (-2525 3900)(-2600 3900);
WIRE 16 -1 (-2525 4000)(-2525 3900);
WIRE 16 -1 (-2525 3900)(-2500 3900);
WIRE 16 -1 (-2500 3900)(-550 3900);
WIRE 16 -1 (-2500 3775)(-2500 3900);
WIRE 16 -1 (-2600 3775)(-2500 3775);
WIRE 16 -1 (-1875 3800)(-550 3800);
FORCEPROP 0 LAST CDS_PHYS_NET_NAME FM_PCH_SLP_S4_N
J 0
(-1850 3842);
PAINT MONO (-1850 3842);
DISPLAY INVISIBLE (-1850 3842);
FORCEPROP 0 LAST SIG_NAME CLK_24M_66M_LPC0_ESPI
J 0
(-1775 3810);
DISPLAY 0.680851 (-1775 3810);
PAINT WHITE (-1775 3810);
WIRE 16 -1 (-1875 3550)(-550 3550);
FORCEPROP 0 LAST CDS_PHYS_NET_NAME FM_PCH_SLP_S4_N
J 0
(-1850 3592);
PAINT MONO (-1850 3592);
DISPLAY INVISIBLE (-1850 3592);
FORCEPROP 0 LAST SIG_NAME ESPI_LAD0_DATA_IO2
J 0
(-1775 3560);
DISPLAY 0.680851 (-1775 3560);
PAINT WHITE (-1775 3560);
WIRE 16 -1 (-1875 3650)(-550 3650);
FORCEPROP 0 LAST CDS_PHYS_NET_NAME FM_PCH_SLP_S4_N
J 0
(-1850 3692);
PAINT MONO (-1850 3692);
DISPLAY INVISIBLE (-1850 3692);
FORCEPROP 0 LAST SIG_NAME ESPI_LFRAME_N_BMC_CS0_N
J 0
(-1775 3660);
DISPLAY 0.680851 (-1775 3660);
PAINT WHITE (-1775 3660);
WIRE 16 -1 (-1875 3500)(-550 3500);
FORCEPROP 0 LAST CDS_PHYS_NET_NAME FM_PCH_SLP_S4_N
J 0
(-1850 3542);
PAINT MONO (-1850 3542);
DISPLAY INVISIBLE (-1850 3542);
FORCEPROP 0 LAST SIG_NAME ESPI_LAD0_DATA_IO1
J 0
(-1775 3510);
DISPLAY 0.680851 (-1775 3510);
PAINT WHITE (-1775 3510);
WIRE 16 -1 (-1875 3400)(-550 3400);
FORCEPROP 0 LAST CDS_PHYS_NET_NAME FM_PCH_SLP_S4_N
J 0
(-1850 3442);
PAINT MONO (-1850 3442);
DISPLAY INVISIBLE (-1850 3442);
FORCEPROP 0 LAST SIG_NAME ESPI_ALERT1_N_LPC_RCIN_N
J 0
(-1775 3410);
DISPLAY 0.680851 (-1775 3410);
PAINT WHITE (-1775 3410);
WIRE 16 2175 (-2900 3700)(-2550 3700);
WIRE 16 2175 (-2550 3950)(-2550 3700);
WIRE 16 2175 (-2900 3950)(-2900 3700);
WIRE 16 2175 (-2900 3950)(-2550 3950);
WIRE 16 -1 (-1875 3050)(-550 3050);
FORCEPROP 0 LAST CDS_PHYS_NET_NAME FM_PCH_SLP_S4_N
J 0
(-1850 3092);
PAINT MONO (-1850 3092);
DISPLAY INVISIBLE (-1850 3092);
FORCEPROP 0 LAST SIG_NAME JTAG_TRC_PCH_PTI<12>
J 0
(-1775 3060);
DISPLAY 0.680851 (-1775 3060);
PAINT WHITE (-1775 3060);
WIRE 16 -1 (-1875 2850)(-550 2850);
FORCEPROP 0 LAST CDS_PHYS_NET_NAME FM_PCH_SLP_S4_N
J 0
(-1850 2892);
PAINT MONO (-1850 2892);
DISPLAY INVISIBLE (-1850 2892);
FORCEPROP 0 LAST SIG_NAME JTAG_TRC_PCH_PTI<8>
J 0
(-1775 2860);
DISPLAY 0.680851 (-1775 2860);
PAINT WHITE (-1775 2860);
WIRE 16 -1 (-1875 2800)(-550 2800);
FORCEPROP 0 LAST CDS_PHYS_NET_NAME FM_PCH_SLP_S4_N
J 0
(-1850 2842);
PAINT MONO (-1850 2842);
DISPLAY INVISIBLE (-1850 2842);
FORCEPROP 0 LAST SIG_NAME JTAG_TRC_PCH_PTI<7>
J 0
(-1775 2810);
DISPLAY 0.680851 (-1775 2810);
PAINT WHITE (-1775 2810);
WIRE 16 -1 (-1875 2900)(-550 2900);
FORCEPROP 0 LAST CDS_PHYS_NET_NAME FM_PCH_SLP_S4_N
J 0
(-1850 2942);
PAINT MONO (-1850 2942);
DISPLAY INVISIBLE (-1850 2942);
FORCEPROP 0 LAST SIG_NAME JTAG_TRC_PCH_PTI<9>
J 0
(-1775 2910);
DISPLAY 0.680851 (-1775 2910);
PAINT WHITE (-1775 2910);
WIRE 16 -1 (-1875 2700)(-550 2700);
FORCEPROP 0 LAST CDS_PHYS_NET_NAME FM_PCH_SLP_S4_N
J 0
(-1850 2742);
PAINT MONO (-1850 2742);
DISPLAY INVISIBLE (-1850 2742);
FORCEPROP 0 LAST SIG_NAME JTAG_TRC_PCH_PTI<5>
J 0
(-1775 2710);
DISPLAY 0.680851 (-1775 2710);
PAINT WHITE (-1775 2710);
WIRE 16 -1 (-1875 2600)(-550 2600);
FORCEPROP 0 LAST SIG_NAME PU_OC5_USB_N
J 0
(-1775 2610);
DISPLAY 0.680851 (-1775 2610);
PAINT WHITE (-1775 2610);
WIRE 16 -1 (-1875 2500)(-550 2500);
FORCEPROP 0 LAST SIG_NAME PU_OC3_USB_N
J 0
(-1775 2510);
DISPLAY 0.680851 (-1775 2510);
PAINT WHITE (-1775 2510);
WIRE 16 -1 (-1875 2300)(-550 2300);
FORCEPROP 0 LAST CDS_PHYS_NET_NAME FM_PCH_SLP_S4_N
J 0
(-1850 2342);
PAINT MONO (-1850 2342);
DISPLAY INVISIBLE (-1850 2342);
FORCEPROP 0 LAST SIG_NAME JTAG_TRC_PCH_PTI<3>
J 0
(-1775 2310);
DISPLAY 0.680851 (-1775 2310);
PAINT WHITE (-1775 2310);
WIRE 16 -1 (-1875 2200)(-550 2200);
FORCEPROP 0 LAST CDS_PHYS_NET_NAME FM_PCH_SLP_S4_N
J 0
(-1850 2242);
PAINT MONO (-1850 2242);
DISPLAY INVISIBLE (-1850 2242);
FORCEPROP 0 LAST SIG_NAME JTAG_TRC_PCH_PTI<1>
J 0
(-1775 2210);
DISPLAY 0.680851 (-1775 2210);
PAINT WHITE (-1775 2210);
WIRE 16 2175 (-2825 -1100)(-825 -1100);
WIRE 16 2175 (-825 -450)(-825 -1100);
WIRE 16 2175 (-2825 -450)(-2825 -1100);
WIRE 16 2175 (-2825 -450)(-825 -450);
WIRE 16 -1 (3375 -225)(1975 -225);
FORCEPROP 2 LAST SIG_NAME PU_OC2_USB_N
J 0
(2190 -215);
DISPLAY 0.680851 (2190 -215);
PAINT WHITE (2190 -215);
WIRE 16 -1 (3575 -1350)(4525 -1350);
WIRE 16 -1 (4525 -1175)(3575 -1175);
WIRE 16 -1 (4525 -1350)(4525 -1175);
WIRE 16 -1 (4525 -1125)(3575 -1125);
WIRE 16 -1 (4525 -1125)(4525 -1175);
WIRE 16 -1 (4525 -1075)(3575 -1075);
WIRE 16 -1 (4525 -1075)(4525 -1125);
WIRE 16 -1 (4525 -975)(3575 -975);
WIRE 16 -1 (4525 -1075)(4525 -975);
WIRE 16 -1 (4525 -925)(3575 -925);
WIRE 16 -1 (4525 -975)(4525 -925);
WIRE 16 -1 (4525 -825)(3575 -825);
WIRE 16 -1 (4525 -925)(4525 -825);
WIRE 16 -1 (4525 -775)(3575 -775);
WIRE 16 -1 (4525 -825)(4525 -775);
WIRE 16 -1 (4525 -675)(3575 -675);
WIRE 16 -1 (4525 -675)(4525 -775);
WIRE 16 -1 (4525 -625)(3575 -625);
WIRE 16 -1 (4525 -675)(4525 -625);
WIRE 16 -1 (4525 -425)(3575 -425);
WIRE 16 -1 (4525 -625)(4525 -425);
WIRE 16 -1 (4525 -375)(3575 -375);
WIRE 16 -1 (4525 -425)(4525 -375);
WIRE 16 -1 (4525 -325)(3575 -325);
WIRE 16 -1 (4525 -375)(4525 -325);
WIRE 16 -1 (4525 -275)(3575 -275);
WIRE 16 -1 (4525 -325)(4525 -275);
WIRE 16 -1 (4525 -225)(3575 -225);
WIRE 16 -1 (4525 -275)(4525 -225);
WIRE 16 -1 (4525 -175)(3575 -175);
WIRE 16 -1 (4525 -225)(4525 -175);
WIRE 16 -1 (4525 -25)(3575 -25);
WIRE 16 -1 (4525 -125)(3575 -125);
WIRE 16 -1 (4525 -175)(4525 -125);
WIRE 16 -1 (4525 -125)(4525 -25);
WIRE 16 -1 (-2825 1525)(-2925 1525);
WIRE 16 -1 (-1325 -600)(-900 -600);
WIRE 16 -1 (-1325 -650)(-900 -650);
WIRE 16 -1 (-900 -600)(-900 -650);
WIRE 16 -1 (-1325 -700)(-900 -700);
WIRE 16 -1 (-900 -650)(-900 -700);
WIRE 16 -1 (-1325 -750)(-900 -750);
WIRE 16 -1 (-900 -700)(-900 -750);
WIRE 16 -1 (-1325 -800)(-900 -800);
WIRE 16 -1 (-900 -750)(-900 -800);
WIRE 16 -1 (-1325 -850)(-900 -850);
WIRE 16 -1 (-900 -850)(-900 -800);
WIRE 16 -1 (-1325 -900)(-900 -900);
WIRE 16 -1 (-900 -900)(-900 -850);
WIRE 16 -1 (-900 -950)(-900 -900);
WIRE 16 -1 (-1325 -950)(-900 -950);
WIRE 16 2175 (1575 -1425)(4575 -1425);
WIRE 16 2175 (4575 -1300)(4575 -1425);
WIRE 16 2175 (1575 -1300)(1575 -1425);
WIRE 16 2175 (1575 -1300)(4575 -1300);
WIRE 16 -1 (1975 -825)(3375 -825);
FORCEPROP 2 LAST SIG_NAME PU_SMB_SML3_3V3AUX_PCH_SDA
J 0
(2190 -815);
DISPLAY 0.680851 (2190 -815);
PAINT WHITE (2190 -815);
WIRE 16 -1 (3375 -775)(1975 -775);
FORCEPROP 2 LAST SIG_NAME PU_SMB_SML3_3V3AUX_PCH_SCL
J 0
(2190 -765);
DISPLAY 0.680851 (2190 -765);
PAINT WHITE (2190 -765);
WIRE 16 -1 (3375 -175)(1975 -175);
FORCEPROP 2 LAST SIG_NAME USB_OC1_REAR_R_N
J 0
(2190 -165);
DISPLAY 0.680851 (2190 -165);
PAINT WHITE (2190 -165);
WIRE 16 -1 (3375 -25)(1975 -25);
FORCEPROP 2 LAST SIG_NAME IRQ_SML0_ALERT_N
J 0
(2190 -15);
DISPLAY 0.680851 (2190 -15);
PAINT WHITE (2190 -15);
WIRE 16 -1 (3375 -275)(1975 -275);
FORCEPROP 2 LAST SIG_NAME PU_OC3_USB_N
J 0
(2190 -265);
DISPLAY 0.680851 (2190 -265);
PAINT WHITE (2190 -265);
WIRE 16 -1 (3375 -325)(1975 -325);
FORCEPROP 2 LAST SIG_NAME PU_OC4_USB_N
J 0
(2190 -315);
DISPLAY 0.680851 (2190 -315);
PAINT WHITE (2190 -315);
WIRE 16 -1 (3375 -375)(1975 -375);
FORCEPROP 2 LAST SIG_NAME PU_OC5_USB_N
J 0
(2190 -365);
DISPLAY 0.680851 (2190 -365);
PAINT WHITE (2190 -365);
WIRE 16 -1 (3375 -425)(1975 -425);
FORCEPROP 2 LAST SIG_NAME PU_OC6_USB_N
J 0
(2190 -415);
DISPLAY 0.680851 (2190 -415);
PAINT WHITE (2190 -415);
WIRE 16 -1 (1975 -1350)(3375 -1350);
FORCEPROP 2 LAST SIG_NAME E1S_0_CLK_OE_N
J 0
(2190 -1340);
DISPLAY 0.702128 (2190 -1340);
PAINT WHITE (2190 -1340);
WIRE 16 -1 (-2450 -700)(-1525 -700);
FORCEPROP 0 LAST CDS_PHYS_NET_NAME FM_PCH_SLP_S4_N
J 0
(-2425 -658);
PAINT MONO (-2425 -658);
DISPLAY INVISIBLE (-2425 -658);
FORCEPROP 0 LAST SIG_NAME PD_PCH_GPPC_A_15
J 0
(-2350 -690);
DISPLAY 0.680851 (-2350 -690);
PAINT WHITE (-2350 -690);
WIRE 16 -1 (-2450 -650)(-1525 -650);
FORCEPROP 0 LAST CDS_PHYS_NET_NAME FM_PCH_SLP_S4_N
J 0
(-2425 -608);
PAINT MONO (-2425 -608);
DISPLAY INVISIBLE (-2425 -608);
FORCEPROP 0 LAST SIG_NAME PD_PCH_GPPC_A_18
J 0
(-2350 -640);
DISPLAY 0.680851 (-2350 -640);
PAINT WHITE (-2350 -640);
WIRE 16 -1 (-2450 -600)(-1525 -600);
FORCEPROP 0 LAST CDS_PHYS_NET_NAME FM_PCH_SLP_S4_N
J 0
(-2425 -558);
PAINT MONO (-2425 -558);
DISPLAY INVISIBLE (-2425 -558);
FORCEPROP 0 LAST SIG_NAME PD_PCH_GPPC_A_19
J 0
(-2350 -590);
DISPLAY 0.680851 (-2350 -590);
PAINT WHITE (-2350 -590);
WIRE 16 -1 (1975 -975)(3375 -975);
FORCEPROP 2 LAST SIG_NAME PU_SMB_SML4_3V3AUX_PCH_SDA
J 0
(2190 -965);
DISPLAY 0.680851 (2190 -965);
PAINT WHITE (2190 -965);
WIRE 16 -1 (1975 -1175)(3375 -1175);
FORCEPROP 2 LAST SIG_NAME PU_PCH_PLD_3V3AUX_ALERT_N
J 0
(2190 -1165);
DISPLAY 0.680851 (2190 -1165);
PAINT WHITE (2190 -1165);
WIRE 16 -1 (3375 -1125)(1975 -1125);
FORCEPROP 2 LAST SIG_NAME PU_SMB_PCH_PLD_3V3AUX_SDA
J 0
(2190 -1115);
DISPLAY 0.680851 (2190 -1115);
PAINT WHITE (2190 -1115);
WIRE 16 -1 (3375 -1075)(1975 -1075);
FORCEPROP 2 LAST SIG_NAME PU_SMB_PCH_PLD_3V3AUX_SCL
J 0
(2190 -1065);
DISPLAY 0.680851 (2190 -1065);
PAINT WHITE (2190 -1065);
WIRE 16 -1 (3375 -925)(1975 -925);
FORCEPROP 2 LAST SIG_NAME PU_SMB_SML4_3V3AUX_PCH_SCL
J 0
(2190 -915);
DISPLAY 0.680851 (2190 -915);
PAINT WHITE (2190 -915);
WIRE 16 -1 (1975 -675)(3375 -675);
FORCEPROP 2 LAST SIG_NAME SMB_SML0B_3V3AUX_SDA
J 0
(2190 -665);
DISPLAY 0.680851 (2190 -665);
PAINT WHITE (2190 -665);
WIRE 16 -1 (3375 -125)(1975 -125);
FORCEPROP 2 LAST SIG_NAME FM_PMBUS_ALERT_B_EN
J 0
(2190 -115);
DISPLAY 0.680851 (2190 -115);
PAINT WHITE (2190 -115);
WIRE 16 -1 (3375 -625)(1975 -625);
FORCEPROP 2 LAST SIG_NAME SMB_SML0B_3V3AUX_SCL
J 0
(2190 -615);
DISPLAY 0.680851 (2190 -615);
PAINT WHITE (2190 -615);
WIRE 16 -1 (3050 650)(4450 650);
FORCEPROP 0 LAST CDS_PHYS_NET_NAME CLK_100M_DB2000_CPU0_BCLK0_DP
J 0
(3590 692);
PAINT MONO (3590 692);
DISPLAY INVISIBLE (3590 692);
FORCEPROP 2 LAST SIG_NAME FM_PCHHOT_R_N
J 0
(3540 660);
DISPLAY 0.680851 (3540 660);
PAINT WHITE (3540 660);
WIRE 16 -1 (3050 775)(4450 775);
FORCEPROP 0 LAST CDS_PHYS_NET_NAME CLK_100M_DB2000_CPU0_BCLK0_DP
J 0
(3590 817);
PAINT MONO (3590 817);
DISPLAY INVISIBLE (3590 817);
FORCEPROP 2 LAST SIG_NAME USB_OC1_REAR_N
J 0
(3540 785);
DISPLAY 0.680851 (3540 785);
PAINT WHITE (3540 785);
WIRE 16 -1 (3050 900)(4450 900);
FORCEPROP 0 LAST CDS_PHYS_NET_NAME CLK_100M_DB2000_CPU0_BCLK0_DP
J 0
(3590 942);
PAINT MONO (3590 942);
DISPLAY INVISIBLE (3590 942);
FORCEPROP 2 LAST SIG_NAME FM_PCH_CRASHLOG_TRIG_N
J 0
(3540 910);
DISPLAY 0.680851 (3540 910);
PAINT WHITE (3540 910);
WIRE 16 -1 (3050 1025)(4450 1025);
FORCEPROP 0 LAST CDS_PHYS_NET_NAME IRQ_SML0_ALERT_R_N
J 0
(3590 1067);
PAINT MONO (3590 1067);
DISPLAY INVISIBLE (3590 1067);
FORCEPROP 2 LAST SIG_NAME IRQ_SML1_PMBUS_BMC_ALERT_N
J 0
(3540 1035);
DISPLAY 0.680851 (3540 1035);
PAINT WHITE (3540 1035);
WIRE 16 -1 (2850 1450)(1625 1450);
FORCEPROP 2 LAST SIG_NAME SMB_SML1_PMBUS_3V3AUX_PCH_SCL
J 0
(1765 1460);
DISPLAY 0.680851 (1765 1460);
PAINT WHITE (1765 1460);
WIRE 16 -1 (2850 1650)(1625 1650);
FORCEPROP 0 LAST CDS_PHYS_NET_NAME CLK_100M_DB2000_CPU0_BCLK0_DP
J 0
(1790 1692);
PAINT MONO (1790 1692);
DISPLAY INVISIBLE (1790 1692);
FORCEPROP 2 LAST SIG_NAME FM_BIOS_DEBUG_EN_N
J 0
(1740 1660);
DISPLAY 0.680851 (1740 1660);
PAINT WHITE (1740 1660);
WIRE 16 -1 (-1875 2250)(-550 2250);
FORCEPROP 0 LAST CDS_PHYS_NET_NAME FM_PCH_SLP_S4_N
J 0
(-1850 2292);
PAINT MONO (-1850 2292);
DISPLAY INVISIBLE (-1850 2292);
FORCEPROP 0 LAST SIG_NAME JTAG_TRC_PCH_PTI<2>
J 0
(-1775 2260);
DISPLAY 0.680851 (-1775 2260);
PAINT WHITE (-1775 2260);
WIRE 16 -1 (-1875 2450)(-550 2450);
FORCEPROP 0 LAST SIG_NAME PU_OC2_USB_N
J 0
(-1775 2460);
DISPLAY 0.680851 (-1775 2460);
PAINT WHITE (-1775 2460);
WIRE 16 -1 (-1875 2550)(-550 2550);
FORCEPROP 0 LAST SIG_NAME PU_OC4_USB_N
J 0
(-1775 2560);
DISPLAY 0.680851 (-1775 2560);
PAINT WHITE (-1775 2560);
WIRE 16 -1 (-3550 3775)(-2800 3775);
FORCEPROP 2 LAST SIG_NAME E1S_0_CLK_OE_N
J 0
(-3545 3785);
DISPLAY 0.702128 (-3545 3785);
PAINT WHITE (-3545 3785);
WIRE 16 -1 (-1875 2350)(-550 2350);
FORCEPROP 0 LAST CDS_PHYS_NET_NAME FM_PCH_SLP_S4_N
J 0
(-1850 2392);
PAINT MONO (-1850 2392);
DISPLAY INVISIBLE (-1850 2392);
FORCEPROP 0 LAST SIG_NAME JTAG_TRC_PCH_PTI<4>
J 0
(-1775 2360);
DISPLAY 0.680851 (-1775 2360);
PAINT WHITE (-1775 2360);
WIRE 16 -1 (-1875 2650)(-550 2650);
FORCEPROP 0 LAST SIG_NAME PU_OC6_USB_N
J 0
(-1775 2660);
DISPLAY 0.680851 (-1775 2660);
PAINT WHITE (-1775 2660);
WIRE 16 -1 (-1875 2750)(-550 2750);
FORCEPROP 0 LAST CDS_PHYS_NET_NAME FM_PCH_SLP_S4_N
J 0
(-1850 2792);
PAINT MONO (-1850 2792);
DISPLAY INVISIBLE (-1850 2792);
FORCEPROP 0 LAST SIG_NAME JTAG_TRC_PCH_PTI<6>
J 0
(-1775 2760);
DISPLAY 0.680851 (-1775 2760);
PAINT WHITE (-1775 2760);
WIRE 16 -1 (-1875 2950)(-550 2950);
FORCEPROP 0 LAST CDS_PHYS_NET_NAME FM_PCH_SLP_S4_N
J 0
(-1850 2992);
PAINT MONO (-1850 2992);
DISPLAY INVISIBLE (-1850 2992);
FORCEPROP 0 LAST SIG_NAME JTAG_TRC_PCH_PTI<10>
J 0
(-1775 2960);
DISPLAY 0.680851 (-1775 2960);
PAINT WHITE (-1775 2960);
WIRE 16 -1 (-1875 3450)(-550 3450);
FORCEPROP 0 LAST CDS_PHYS_NET_NAME FM_PCH_SLP_S4_N
J 0
(-1850 3492);
PAINT MONO (-1850 3492);
DISPLAY INVISIBLE (-1850 3492);
FORCEPROP 0 LAST SIG_NAME ESPI_LAD0_DATA_IO0
J 0
(-1775 3460);
DISPLAY 0.680851 (-1775 3460);
PAINT WHITE (-1775 3460);
WIRE 16 -1 (-3550 3900)(-2800 3900);
FORCEPROP 2 LAST SIG_NAME E1S_0_PRSNT_N
J 0
(-3545 3910);
DISPLAY 0.702128 (-3545 3910);
PAINT WHITE (-3545 3910);
WIRE 16 -1 (-1725 1475)(-2925 1475);
FORCEPROP 2 LAST SIG_NAME SMB_SML0_3V3AUX_PCH_SDA
J 0
(-2710 1485);
DISPLAY 0.680851 (-2710 1485);
PAINT WHITE (-2710 1485);
WIRE 16 -1 (-1725 900)(-2925 900);
FORCEPROP 2 LAST SIG_NAME SMB_SML1_PMBUS_3V3AUX_PCH_SDA_R1
J 0
(-2710 910);
DISPLAY 0.680851 (-2710 910);
PAINT WHITE (-2710 910);
WIRE 16 -1 (-1875 3750)(-550 3750);
FORCEPROP 0 LAST CDS_PHYS_NET_NAME FM_PCH_SLP_S4_N
J 0
(-1850 3792);
PAINT MONO (-1850 3792);
DISPLAY INVISIBLE (-1850 3792);
FORCEPROP 0 LAST SIG_NAME RST_ESPI_RESET_N
J 0
(-1775 3760);
DISPLAY 0.680851 (-1775 3760);
PAINT WHITE (-1775 3760);
WIRE 16 -1 (-1875 3850)(-550 3850);
FORCEPROP 0 LAST CDS_PHYS_NET_NAME FM_PCH_SLP_S4_N
J 0
(-1850 3892);
PAINT MONO (-1850 3892);
DISPLAY INVISIBLE (-1850 3892);
FORCEPROP 0 LAST SIG_NAME PD_PCH_GPPC_A_10
J 0
(-1785 3860);
DISPLAY 0.680851 (-1785 3860);
PAINT WHITE (-1785 3860);
WIRE 16 -1 (-1875 3950)(-550 3950);
FORCEPROP 0 LAST CDS_PHYS_NET_NAME FM_PCH_SLP_S4_N
J 0
(-1850 3992);
PAINT MONO (-1850 3992);
DISPLAY INVISIBLE (-1850 3992);
FORCEPROP 0 LAST SIG_NAME M2_SSD0_CLKREQ_EN_N
J 0
(-1775 3960);
DISPLAY 0.680851 (-1775 3960);
PAINT WHITE (-1775 3960);
WIRE 16 -1 (-3550 4000)(-2800 4000);
FORCEPROP 0 LAST CDS_PHYS_NET_NAME E1S_0_PERST1_CLKREQ_N
J 0
(-3525 4042);
PAINT MONO (-3525 4042);
DISPLAY INVISIBLE (-3525 4042);
FORCEPROP 0 LAST SIG_NAME E1S_0_PERST1_CLKREQ_N
J 0
(-3560 4010);
DISPLAY 0.680851 (-3560 4010);
PAINT WHITE (-3560 4010);
WIRE 16 -1 (3200 4300)(4400 4300);
FORCEPROP 2 LAST SIG_NAME PU_PCH_PLD_3V3AUX_ALERT_N
J 0
(3415 4310);
DISPLAY 0.680851 (3415 4310);
PAINT WHITE (3415 4310);
WIRE 16 -1 (4400 4250)(3200 4250);
FORCEPROP 2 LAST SIG_NAME PU_SMB_PCH_PLD_3V3AUX_SDA
J 0
(3415 4260);
DISPLAY 0.680851 (3415 4260);
PAINT WHITE (3415 4260);
WIRE 16 -1 (4400 4200)(3200 4200);
FORCEPROP 2 LAST SIG_NAME PU_SMB_PCH_PLD_3V3AUX_SCL
J 0
(3415 4210);
DISPLAY 0.680851 (3415 4210);
PAINT WHITE (3415 4210);
WIRE 16 -1 (4400 4150)(3200 4150);
FORCEPROP 2 LAST SIG_NAME FM_ADR_MODE1
J 0
(3415 4160);
DISPLAY 0.680851 (3415 4160);
PAINT WHITE (3415 4160);
WIRE 16 -1 (4400 4100)(3200 4100);
FORCEPROP 2 LAST SIG_NAME FM_BIOS_POST_CMPLT_N
J 0
(3415 4110);
DISPLAY 0.680851 (3415 4110);
PAINT WHITE (3415 4110);
WIRE 16 -1 (4400 3950)(3200 3950);
FORCEPROP 2 LAST SIG_NAME FM_THROTTLE_N
J 0
(3415 3960);
DISPLAY 0.680851 (3415 3960);
PAINT WHITE (3415 3960);
WIRE 16 -1 (4400 3850)(3200 3850);
FORCEPROP 2 LAST SIG_NAME PU_SMB_SML3_3V3AUX_PCH_SCL
J 0
(3415 3860);
DISPLAY 0.680851 (3415 3860);
PAINT WHITE (3415 3860);
WIRE 16 -1 (4400 3900)(3200 3900);
FORCEPROP 2 LAST SIG_NAME PU_SMB_SML3_3V3AUX_PCH_SDA
J 0
(3415 3910);
DISPLAY 0.680851 (3415 3910);
PAINT WHITE (3415 3910);
WIRE 16 -1 (4400 4000)(3200 4000);
FORCEPROP 2 LAST SIG_NAME PU_SMB_SML4_3V3AUX_PCH_SCL
J 0
(3415 4010);
DISPLAY 0.680851 (3415 4010);
PAINT WHITE (3415 4010);
WIRE 16 -1 (4400 4050)(3200 4050);
FORCEPROP 2 LAST SIG_NAME PU_SMB_SML4_3V3AUX_PCH_SDA
J 0
(3415 4060);
DISPLAY 0.680851 (3415 4060);
PAINT WHITE (3415 4060);
WIRE 16 -1 (4400 3750)(3200 3750);
FORCEPROP 2 LAST SIG_NAME PD_PCH_GPPC_C10
J 0
(3415 3760);
DISPLAY 0.680851 (3415 3760);
PAINT WHITE (3415 3760);
WIRE 16 -1 (4400 3700)(3200 3700);
FORCEPROP 2 LAST SIG_NAME PD_PCH_GPPC_C9
J 0
(3415 3710);
DISPLAY 0.680851 (3415 3710);
PAINT WHITE (3415 3710);
WIRE 16 -1 (4400 3600)(3200 3600);
FORCEPROP 2 LAST SIG_NAME SMB_SML1_PMBUS_3V3AUX_PCH_SDA_R1
J 0
(3415 3610);
DISPLAY 0.680851 (3415 3610);
PAINT WHITE (3415 3610);
WIRE 16 -1 (4400 3650)(3200 3650);
FORCEPROP 2 LAST SIG_NAME IRQ_SML1_PMBUS_ALERT_N
J 0
(3415 3660);
DISPLAY 0.680851 (3415 3660);
PAINT WHITE (3415 3660);
WIRE 16 -1 (4400 3800)(3200 3800);
FORCEPROP 2 LAST SIG_NAME FM_PMBUS_ALERT_B_EN
J 0
(3415 3810);
DISPLAY 0.680851 (3415 3810);
PAINT WHITE (3415 3810);
WIRE 16 -1 (3200 3500)(4400 3500);
FORCEPROP 2 LAST SIG_NAME PD_PCH_GPPC_C5
J 0
(3415 3510);
DISPLAY 0.680851 (3415 3510);
PAINT WHITE (3415 3510);
WIRE 16 -1 (4400 3550)(3200 3550);
FORCEPROP 2 LAST SIG_NAME SMB_SML1_PMBUS_3V3AUX_PCH_SCL_R1
J 0
(3415 3560);
DISPLAY 0.680851 (3415 3560);
PAINT WHITE (3415 3560);
WIRE 16 -1 (3200 3350)(4400 3350);
FORCEPROP 2 LAST SIG_NAME IRQ_SML0_ALERT_N
J 0
(3415 3360);
DISPLAY 0.680851 (3415 3360);
PAINT WHITE (3415 3360);
WIRE 16 -1 (4400 3400)(3200 3400);
FORCEPROP 2 LAST SIG_NAME SMB_SML0B_3V3AUX_SDA
J 0
(3415 3410);
DISPLAY 0.680851 (3415 3410);
PAINT WHITE (3415 3410);
WIRE 16 -1 (4400 3450)(3200 3450);
FORCEPROP 2 LAST SIG_NAME SMB_SML0B_3V3AUX_SCL
J 0
(3415 3460);
DISPLAY 0.680851 (3415 3460);
PAINT WHITE (3415 3460);
WIRE 16 -1 (3200 3100)(4400 3100);
FORCEPROP 2 LAST SIG_NAME FM_BIOS_DEBUG_EN_R_N
J 0
(3415 3110);
DISPLAY 0.680851 (3415 3110);
PAINT WHITE (3415 3110);
WIRE 16 -1 (4400 3250)(3200 3250);
FORCEPROP 2 LAST SIG_NAME SMB_SML0_3V3AUX_PCH_SCL
J 0
(3415 3260);
DISPLAY 0.680851 (3415 3260);
PAINT WHITE (3415 3260);
WIRE 16 -1 (4400 3300)(3200 3300);
FORCEPROP 2 LAST SIG_NAME SMB_SML0_3V3AUX_PCH_SDA
J 0
(3415 3310);
DISPLAY 0.680851 (3415 3310);
PAINT WHITE (3415 3310);
WIRE 16 -1 (3200 3150)(4400 3150);
FORCEPROP 2 LAST SIG_NAME FM_PCH_BOOT_BIOS_STRAP
J 0
(3415 3160);
DISPLAY 0.680851 (3415 3160);
PAINT WHITE (3415 3160);
WIRE 16 -1 (4400 3050)(3200 3050);
FORCEPROP 2 LAST SIG_NAME FM_PCH_GLB_RST_WARN_N
J 0
(3415 3060);
DISPLAY 0.680851 (3415 3060);
PAINT WHITE (3415 3060);
WIRE 16 -1 (4400 2850)(3200 2850);
FORCEPROP 2 LAST SIG_NAME FM_PLT_BMC_THERMTRIP_R_N
J 0
(3415 2860);
DISPLAY 0.680851 (3415 2860);
PAINT WHITE (3415 2860);
WIRE 16 -1 (3200 2900)(4400 2900);
FORCEPROP 2 LAST SIG_NAME FM_CPU_RMCA_CATERR_DLY_N
J 0
(3415 2910);
DISPLAY 0.680851 (3415 2910);
PAINT WHITE (3415 2910);
WIRE 16 -1 (3200 2950)(4400 2950);
FORCEPROP 2 LAST SIG_NAME FM_BIOS_IMAGE_SWAP_N
J 0
(3415 2960);
DISPLAY 0.680851 (3415 2960);
PAINT WHITE (3415 2960);
WIRE 16 -1 (4400 2600)(3200 2600);
FORCEPROP 2 LAST SIG_NAME FM_PCHHOT_N
J 0
(3415 2610);
DISPLAY 0.680851 (3415 2610);
PAINT WHITE (3415 2610);
WIRE 16 -1 (4400 2650)(3200 2650);
FORCEPROP 2 LAST SIG_NAME FM_ADR_COMPLETE
J 0
(3415 2660);
DISPLAY 0.680851 (3415 2660);
PAINT WHITE (3415 2660);
WIRE 16 -1 (3200 2700)(4400 2700);
FORCEPROP 2 LAST SIG_NAME FM_ADR_TRIGGER_R_N
J 0
(3415 2710);
DISPLAY 0.680851 (3415 2710);
PAINT WHITE (3415 2710);
WIRE 16 -1 (3200 2750)(4400 2750);
FORCEPROP 2 LAST SIG_NAME PU_PCH_VRALERT_N
J 0
(3415 2760);
DISPLAY 0.680851 (3415 2760);
PAINT WHITE (3415 2760);
WIRE 16 -1 (3200 2800)(4400 2800);
FORCEPROP 2 LAST SIG_NAME FM_ADR_ACK
J 0
(3415 2810);
DISPLAY 0.680851 (3415 2810);
PAINT WHITE (3415 2810);
WIRE 16 -1 (3200 2500)(4400 2500);
FORCEPROP 2 LAST SIG_NAME IRQ_PCH_SCI_WHEA_N
J 0
(3415 2510);
DISPLAY 0.680851 (3415 2510);
PAINT WHITE (3415 2510);
WIRE 16 -1 (3200 2450)(4400 2450);
FORCEPROP 2 LAST SIG_NAME PU_LPC_PME_N
J 0
(3415 2460);
DISPLAY 0.680851 (3415 2460);
PAINT WHITE (3415 2460);
WIRE 16 -1 (3200 2400)(4400 2400);
FORCEPROP 2 LAST SIG_NAME FM_PCH_CRASHLOG_TRIG_N
J 0
(3415 2410);
DISPLAY 0.680851 (3415 2410);
PAINT WHITE (3415 2410);
WIRE 16 -1 (3200 2350)(4400 2350);
FORCEPROP 2 LAST SIG_NAME FM_ESPI_FLASH_MODE
J 0
(3415 2360);
DISPLAY 0.680851 (3415 2360);
PAINT WHITE (3415 2360);
WIRE 16 -1 (4400 2550)(3200 2550);
FORCEPROP 2 LAST SIG_NAME RST_PLTRST_N
J 0
(3415 2560);
DISPLAY 0.680851 (3415 2560);
PAINT WHITE (3415 2560);
WIRE 16 -1 (4400 2150)(3200 2150);
FORCEPROP 2 LAST SIG_NAME SMB_HOST_BMC_3V3AUX_SCL
J 0
(3415 2160);
DISPLAY 0.680851 (3415 2160);
PAINT WHITE (3415 2160);
WIRE 16 -1 (3200 2300)(4400 2300);
FORCEPROP 2 LAST SIG_NAME FM_FLASH_SECURITY_STRAP
J 0
(3415 2310);
DISPLAY 0.680851 (3415 2310);
PAINT WHITE (3415 2310);
WIRE 16 -1 (4400 2200)(3200 2200);
FORCEPROP 2 LAST SIG_NAME SMB_HOST_BMC_3V3AUX_SDA
J 0
(3415 2210);
DISPLAY 0.680851 (3415 2210);
PAINT WHITE (3415 2210);
WIRE 16 -1 (-1875 4300)(-550 4300);
FORCEPROP 0 LAST CDS_PHYS_NET_NAME FM_PCH_SLP_S4_N
J 0
(-1850 4342);
PAINT MONO (-1850 4342);
DISPLAY INVISIBLE (-1850 4342);
FORCEPROP 0 LAST SIG_NAME PD_PCH_GPPC_A_19
J 0
(-1775 4310);
DISPLAY 0.680851 (-1775 4310);
PAINT WHITE (-1775 4310);
WIRE 16 -1 (-1875 4250)(-550 4250);
FORCEPROP 0 LAST CDS_PHYS_NET_NAME FM_PCH_SLP_S4_N
J 0
(-1850 4292);
PAINT MONO (-1850 4292);
DISPLAY INVISIBLE (-1850 4292);
FORCEPROP 0 LAST SIG_NAME PD_PCH_GPPC_A_18
J 0
(-1775 4260);
DISPLAY 0.680851 (-1775 4260);
PAINT WHITE (-1775 4260);
WIRE 16 -1 (-1875 4200)(-550 4200);
FORCEPROP 0 LAST CDS_PHYS_NET_NAME FM_PCH_SLP_S4_N
J 0
(-1850 4242);
PAINT MONO (-1850 4242);
DISPLAY INVISIBLE (-1850 4242);
FORCEPROP 0 LAST SIG_NAME IRQ_BMC_PCH_NMI
J 0
(-1775 4210);
DISPLAY 0.680851 (-1775 4210);
PAINT WHITE (-1775 4210);
WIRE 16 -1 (-1875 2150)(-550 2150);
FORCEPROP 0 LAST CDS_PHYS_NET_NAME FM_PCH_SLP_S4_N
J 0
(-1850 2192);
PAINT MONO (-1850 2192);
DISPLAY INVISIBLE (-1850 2192);
FORCEPROP 0 LAST SIG_NAME JTAG_TRC_PCH_PTI<0>
J 0
(-1775 2160);
DISPLAY 0.680851 (-1775 2160);
PAINT WHITE (-1775 2160);
WIRE 16 -1 (-1875 2100)(-550 2100);
FORCEPROP 0 LAST CDS_PHYS_NET_NAME FM_PCH_SLP_S4_N
J 0
(-1850 2142);
PAINT MONO (-1850 2142);
DISPLAY INVISIBLE (-1850 2142);
FORCEPROP 0 LAST SIG_NAME JTAG_TRC_PCH_PTI0_CLK
J 0
(-1775 2110);
DISPLAY 0.680851 (-1775 2110);
PAINT WHITE (-1775 2110);
WIRE 16 -1 (-1875 2400)(-550 2400);
FORCEPROP 0 LAST SIG_NAME USB_OC1_REAR_R_N
J 0
(-1775 2410);
DISPLAY 0.680851 (-1775 2410);
PAINT WHITE (-1775 2410);
WIRE 16 -1 (3200 2250)(4400 2250);
FORCEPROP 2 LAST SIG_NAME TP_PCH_GPP_D_2
J 0
(3415 2260);
DISPLAY 0.680851 (3415 2260);
PAINT WHITE (3415 2260);
WIRE 16 -1 (3200 3000)(4400 3000);
FORCEPROP 2 LAST SIG_NAME TP_PCH_GPP_D_20
J 0
(3415 3010);
DISPLAY 0.680851 (3415 3010);
PAINT WHITE (3415 3010);
WIRE 16 -1 (-2450 -750)(-1525 -750);
FORCEPROP 0 LAST CDS_PHYS_NET_NAME FM_PCH_SLP_S4_N
J 0
(-2425 -708);
PAINT MONO (-2425 -708);
DISPLAY INVISIBLE (-2425 -708);
FORCEPROP 0 LAST SIG_NAME PD_PCH_GPPC_A_14
J 0
(-2350 -740);
DISPLAY 0.680851 (-2350 -740);
PAINT WHITE (-2350 -740);
WIRE 16 -1 (-2450 -800)(-1525 -800);
FORCEPROP 0 LAST CDS_PHYS_NET_NAME FM_PCH_SLP_S4_N
J 0
(-2425 -758);
PAINT MONO (-2425 -758);
DISPLAY INVISIBLE (-2425 -758);
FORCEPROP 0 LAST SIG_NAME PD_PCH_GPPC_A_10
J 0
(-2335 -790);
DISPLAY 0.680851 (-2335 -790);
PAINT WHITE (-2335 -790);
WIRE 16 -1 (-1525 -850)(-2450 -850);
FORCEPROP 2 LAST SIG_NAME PD_PCH_GPPC_C10
J 0
(-2335 -840);
DISPLAY 0.680851 (-2335 -840);
PAINT WHITE (-2335 -840);
WIRE 16 -1 (-2450 -950)(-1525 -950);
FORCEPROP 2 LAST SIG_NAME PD_PCH_GPPC_C5
J 0
(-2335 -940);
DISPLAY 0.680851 (-2335 -940);
PAINT WHITE (-2335 -940);
WIRE 16 -1 (2850 1500)(1625 1500);
FORCEPROP 2 LAST SIG_NAME SMB_SML1_PMBUS_3V3AUX_PCH_SDA
J 0
(1765 1510);
DISPLAY 0.680851 (1765 1510);
PAINT WHITE (1765 1510);
WIRE 16 -1 (2850 1275)(1650 1275);
FORCEPROP 0 LAST CDS_PHYS_NET_NAME CLK_100M_DB2000_CPU0_BCLK0_DP
J 0
(1815 1317);
PAINT MONO (1815 1317);
DISPLAY INVISIBLE (1815 1317);
FORCEPROP 2 LAST SIG_NAME IRQ_SML0_ALERT_N
J 0
(1765 1285);
DISPLAY 0.680851 (1765 1285);
PAINT WHITE (1765 1285);
WIRE 16 -1 (3050 1150)(4450 1150);
FORCEPROP 0 LAST CDS_PHYS_NET_NAME IRQ_SML0_ALERT_R_N
J 0
(3590 1192);
PAINT MONO (3590 1192);
DISPLAY INVISIBLE (3590 1192);
FORCEPROP 2 LAST SIG_NAME IRQ_SML1_PMBUS_PLD_ALERT_N
J 0
(3540 1160);
DISPLAY 0.680851 (3540 1160);
PAINT WHITE (3540 1160);
WIRE 16 -1 (3050 1275)(4450 1275);
FORCEPROP 0 LAST CDS_PHYS_NET_NAME CLK_100M_DB2000_CPU0_BCLK0_DP
J 0
(3590 1317);
PAINT MONO (3590 1317);
DISPLAY INVISIBLE (3590 1317);
FORCEPROP 2 LAST SIG_NAME IRQ_SML0_ALERT_R_N
J 0
(3540 1285);
DISPLAY 0.680851 (3540 1285);
PAINT WHITE (3540 1285);
WIRE 16 -1 (2850 300)(1650 300);
FORCEPROP 0 LAST CDS_PHYS_NET_NAME FM_PCH_SATA_RAID_KEY
J 0
(1815 342);
PAINT MONO (1815 342);
DISPLAY INVISIBLE (1815 342);
FORCEPROP 2 LAST SIG_NAME FM_PCH_SATA_RAID_KEY
J 0
(1815 310);
DISPLAY 0.680851 (1815 310);
PAINT WHITE (1815 310);
WIRE 16 -1 (2850 650)(1650 650);
FORCEPROP 0 LAST CDS_PHYS_NET_NAME CLK_100M_DB2000_CPU0_BCLK0_DP
J 0
(1815 692);
PAINT MONO (1815 692);
DISPLAY INVISIBLE (1815 692);
FORCEPROP 2 LAST SIG_NAME FM_PCHHOT_N
J 0
(1765 660);
DISPLAY 0.680851 (1765 660);
PAINT WHITE (1765 660);
WIRE 16 -1 (2850 775)(1650 775);
FORCEPROP 0 LAST CDS_PHYS_NET_NAME CLK_100M_DB2000_CPU0_BCLK0_DP
J 0
(1815 817);
PAINT MONO (1815 817);
DISPLAY INVISIBLE (1815 817);
FORCEPROP 2 LAST SIG_NAME USB_OC1_REAR_R_N
J 0
(1765 785);
DISPLAY 0.680851 (1765 785);
PAINT WHITE (1765 785);
WIRE 16 -1 (2850 900)(1650 900);
FORCEPROP 0 LAST CDS_PHYS_NET_NAME CLK_100M_DB2000_CPU0_BCLK0_DP
J 0
(1815 942);
PAINT MONO (1815 942);
DISPLAY INVISIBLE (1815 942);
FORCEPROP 2 LAST SIG_NAME FM_PCH_CRASHLOG_TRIG_R_N
J 0
(1765 910);
DISPLAY 0.680851 (1765 910);
PAINT WHITE (1765 910);
WIRE 16 -1 (2575 1025)(2850 1025);
WIRE 16 -1 (2575 1150)(2575 1025);
WIRE 16 -1 (2850 1150)(2575 1150);
WIRE 16 -1 (1650 1150)(2575 1150);
FORCEPROP 0 LAST CDS_PHYS_NET_NAME IRQ_SML0_ALERT_N
J 0
(1815 1192);
PAINT MONO (1815 1192);
DISPLAY INVISIBLE (1815 1192);
FORCEPROP 2 LAST SIG_NAME IRQ_SML1_PMBUS_ALERT_N
J 0
(1765 1160);
DISPLAY 0.680851 (1765 1160);
PAINT WHITE (1765 1160);
WIRE 16 -1 (-1525 -900)(-2450 -900);
FORCEPROP 2 LAST SIG_NAME PD_PCH_GPPC_C9
J 0
(-2335 -890);
DISPLAY 0.680851 (-2335 -890);
PAINT WHITE (-2335 -890);
WIRE 16 -1 (-1425 75)(-1200 75);
WIRE 16 -1 (-1425 225)(-1425 75);
WIRE 16 -1 (-725 225)(-1425 225);
FORCEPROP 0 LAST CDS_PHYS_NET_NAME IRQ_BMC_PCH_NMI
J 0
(-1210 267);
PAINT MONO (-1210 267);
DISPLAY INVISIBLE (-1210 267);
FORCEPROP 2 LAST SIG_NAME IRQ_BMC_PCH_NMI
J 0
(-1335 235);
DISPLAY 0.680851 (-1335 235);
PAINT WHITE (-1335 235);
WIRE 16 -1 (-1750 225)(-1425 225);
WIRE 16 -1 (4425 1450)(3050 1450);
FORCEPROP 2 LAST SIG_NAME SMB_SML1_PMBUS_3V3AUX_PCH_SCL_R1
J 0
(3390 1460);
DISPLAY 0.680851 (3390 1460);
PAINT WHITE (3390 1460);
WIRE 16 -1 (4425 1500)(3050 1500);
FORCEPROP 2 LAST SIG_NAME SMB_SML1_PMBUS_3V3AUX_PCH_SDA_R1
J 0
(3390 1510);
DISPLAY 0.680851 (3390 1510);
PAINT WHITE (3390 1510);
WIRE 16 -1 (3050 1650)(4450 1650);
FORCEPROP 0 LAST CDS_PHYS_NET_NAME CLK_100M_DB2000_CPU0_BCLK0_DP
J 0
(3590 1692);
PAINT MONO (3590 1692);
DISPLAY INVISIBLE (3590 1692);
FORCEPROP 2 LAST SIG_NAME FM_BIOS_DEBUG_EN_R_N
J 0
(3540 1660);
DISPLAY 0.680851 (3540 1660);
PAINT WHITE (3540 1660);
WIRE 16 -1 (-2925 225)(-1950 225);
FORCEPROP 0 LAST CDS_PHYS_NET_NAME FM_PCH_SLP_S4_N
J 0
(-2900 267);
PAINT MONO (-2900 267);
DISPLAY INVISIBLE (-2900 267);
FORCEPROP 0 LAST SIG_NAME IRQ_BMC_PCH_NMI_R
J 0
(-2825 235);
DISPLAY 0.680851 (-2825 235);
PAINT WHITE (-2825 235);
WIRE 16 -1 (-1725 1575)(-2925 1575);
FORCEPROP 2 LAST SIG_NAME SMB_SML0_3V3AUX_PCH_SCL
J 0
(-2710 1585);
DISPLAY 0.680851 (-2710 1585);
PAINT WHITE (-2710 1585);
DOT 1 (-900 -750);
DOT 1 (-900 -950);
DOT 1 (-900 -850);
DOT 1 (4525 -775);
DOT 1 (4525 -1175);
DOT 1 (-2500 3900);
DOT 1 (2575 1150);
DOT 1 (-1425 225);
DOT 1 (-900 -900);
DOT 1 (-900 -650);
DOT 1 (4525 -325);
DOT 1 (4525 -375);
DOT 1 (4525 -425);
DOT 1 (4525 -625);
DOT 1 (4525 -675);
DOT 1 (4525 -825);
DOT 1 (4525 -925);
DOT 1 (4525 -975);
DOT 1 (4525 -1075);
DOT 1 (4525 -1125);
DOT 1 (4525 -275);
DOT 1 (4525 -225);
DOT 1 (4525 -175);
DOT 1 (4525 -125);
DOT 1 (4525 -25);
DOT 1 (-900 -800);
DOT 1 (-2525 3900);
DOT 1 (-900 -700);
FORCENOTE
20220805 ADD R4766,DEPOP R4084
(-3825 3575) 0;
DISPLAY LEFT (-3825 3575);
DISPLAY 1.021277 (-3825 3575);
PAINT PINK (-3825 3575);
FORCENOTE
20220805 ADD R4768
(450 -1375) 0;
DISPLAY LEFT (450 -1375);
DISPLAY 1.276596 (450 -1375);
PAINT PINK (450 -1375);
FORCENOTE
20211130 ADD 10K OHM PD
(-2500 -1225) 0;
DISPLAY LEFT (-2500 -1225);
DISPLAY 1.276596 (-2500 -1225);
PAINT PINK (-2500 -1225);
FORCENOTE
20210602 MODIFY FOR GT
(-3750 4775) 0;
DISPLAY LEFT (-3750 4775);
DISPLAY 1.595745 (-3750 4775);
PAINT PINK (-3750 4775);
FORCENOTE
ENABLE BMC CLKREQ
(1450 450) 0;
DISPLAY LEFT (1450 450);
DISPLAY 1.021277 (1450 450);
PAINT YELLOW (1450 450);
QUIT
